FILE_TYPE = MACRO_DRAWING;
SET COLOR_WIRE YELLOW;
SET COLOR_PROP ORANGE;
SET COLOR_DOT WHITE;
SET COLOR_ARC YELLOW;
SET COLOR_BODY GREEN;
SET COLOR_NOTE PURPLE;
SET PROP_DISPLAY VALUE;
SET PAGE_NUMBER P307;
FORCEADD UNIVERSAL_GND..1
(275 -850);
FORCEPROP 3 LASTPIN (275 -800) SIG_NAME GND\g
J 0
(285 -790);
DISPLAY 0.659574 (285 -790);
PAINT MONO (285 -790);
DISPLAY INVISIBLE (285 -790);
FORCEPROP 2 LAST CDS_LIB pure_quanta_power
J 0
(275 -850);
PAINT MONO (275 -850);
DISPLAY INVISIBLE (275 -850);
FORCEPROP 1 LAST HDL_POWER GND
J 1
(300 -925);
DISPLAY 0.872340 (300 -925);
PAINT GREEN (300 -925);
DISPLAY INVISIBLE (300 -925);
FORCEPROP 1 LAST PATH I14
J 0
(350 -850);
DISPLAY 0.872340 (350 -850);
PAINT AQUA (350 -850);
DISPLAY INVISIBLE (350 -850);
FORCEADD Q_RES..2
(275 -625);
FORCEPROP 1 LAST LOCATION R3207
J 0
(320 -500);
DISPLAY 0.787234 (320 -500);
FORCEPROP 2 LAST $SEC 1
J 0
(325 -400);
DISPLAY 0.680851 (325 -400);
PAINT MONO (325 -400);
DISPLAY INVISIBLE (325 -400);
FORCEPROP 2 LAST CDS_SEC 1
J 0
(325 -400);
DISPLAY 1.021277 (325 -400);
DISPLAY INVISIBLE (325 -400);
FORCEPROP 1 LASTPIN (275 -525) $PN 1
J 0
(280 -563);
DISPLAY 0.787234 (280 -563);
FORCEPROP 1 LASTPIN (275 -725) $PN 2
J 0
(280 -715);
DISPLAY 0.787234 (280 -715);
FORCEPROP 1 LAST TOLERANCE 1%
J 0
(320 -600);
DISPLAY 0.638298 (320 -600);
FORCEPROP 1 LAST VALUE 100K
J 0
(320 -550);
DISPLAY 0.638298 (320 -550);
FORCEPROP 1 LAST WATTAGE 1/16W
J 0
(315 -650);
DISPLAY 0.638298 (315 -650);
FORCEPROP 1 LAST MATERIAL CHIP
J 0
(315 -700);
DISPLAY 0.638298 (315 -700);
FORCEPROP 1 LAST PACK_TYPE 0402LF
J 0
(315 -800);
DISPLAY 0.638298 (315 -800);
FORCEPROP 2 LAST CDS_LIB pure_quanta
J 0
(275 -625);
PAINT MONO (275 -625);
DISPLAY INVISIBLE (275 -625);
FORCEPROP 1 LAST PATH I15
J 0
(325 -450);
DISPLAY 0.978723 (325 -450);
PAINT WHITE (325 -450);
DISPLAY INVISIBLE (325 -450);
FORCEPROP 1 LAST PART_NUMBER CS41002FB09
J 0
(315 -750);
DISPLAY 0.638298 (315 -750);
DISPLAY INVISIBLE (315 -750);
FORCEADD Q_CAP..1
R 2
(-1600 -25);
FORCEPROP 1 LAST LOCATION C1825
J 2
(-1650 75);
DISPLAY 0.978723 (-1650 75);
FORCEPROP 2 LAST $SEC 1
J 0
(-1650 175);
DISPLAY 0.680851 (-1650 175);
PAINT MONO (-1650 175);
DISPLAY INVISIBLE (-1650 175);
FORCEPROP 2 LAST CDS_SEC 1
J 0
(-1650 175);
DISPLAY 1.021277 (-1650 175);
DISPLAY INVISIBLE (-1650 175);
FORCEPROP 1 LASTPIN (-1600 75) $PN 1
J 2
(-1610 55);
DISPLAY 0.787234 (-1610 55);
FORCEPROP 1 LASTPIN (-1600 -125) $PN 2
J 2
(-1610 -145);
DISPLAY 0.787234 (-1610 -145);
FORCEPROP 1 LAST PACK_TYPE 0402
J 2
(-1650 -225);
DISPLAY 0.510638 (-1650 -225);
FORCEPROP 1 LAST TOLERANCE 10%
J 2
(-1650 -75);
DISPLAY 0.510638 (-1650 -75);
FORCEPROP 1 LAST VALUE 0.1UF
J 2
(-1650 25);
DISPLAY 0.510638 (-1650 25);
FORCEPROP 1 LAST VOLTAGE 25V
J 2
(-1650 -25);
DISPLAY 0.510638 (-1650 -25);
FORCEPROP 1 LAST MATERIAL X7R
J 2
(-1650 -125);
DISPLAY 0.510638 (-1650 -125);
FORCEPROP 2 LAST CDS_LIB pure_quanta
J 0
(-1600 -25);
PAINT MONO (-1600 -25);
DISPLAY INVISIBLE (-1600 -25);
FORCEPROP 1 LAST PATH I17
J 2
(-1650 125);
DISPLAY 0.978723 (-1650 125);
PAINT WHITE (-1650 125);
DISPLAY INVISIBLE (-1650 125);
FORCEPROP 1 LAST PART_NUMBER CH4104K1B00
J 2
(-1650 -175);
DISPLAY 0.510638 (-1650 -175);
DISPLAY INVISIBLE (-1650 -175);
FORCEADD UNIVERSAL_GND..1
(-1600 -250);
FORCEPROP 3 LASTPIN (-1600 -200) SIG_NAME GND\g
J 0
(-1590 -190);
DISPLAY 0.659574 (-1590 -190);
PAINT MONO (-1590 -190);
DISPLAY INVISIBLE (-1590 -190);
FORCEPROP 2 LAST CDS_LIB pure_quanta_power
J 0
(-1600 -250);
PAINT MONO (-1600 -250);
DISPLAY INVISIBLE (-1600 -250);
FORCEPROP 1 LAST HDL_POWER GND
J 1
(-1575 -325);
DISPLAY 0.872340 (-1575 -325);
PAINT GREEN (-1575 -325);
DISPLAY INVISIBLE (-1575 -325);
FORCEPROP 1 LAST PATH I18
J 0
(-1525 -250);
DISPLAY 0.872340 (-1525 -250);
PAINT AQUA (-1525 -250);
DISPLAY INVISIBLE (-1525 -250);
FORCEADD UNIVERSAL_POWER..1
(-1600 250);
FORCEPROP 3 LASTPIN (-1600 200) SIG_NAME P3V3_AUX\g
J 0
(-1590 210);
DISPLAY 0.659574 (-1590 210);
PAINT MONO (-1590 210);
DISPLAY INVISIBLE (-1590 210);
FORCEPROP 1 LAST HDL_POWER P3V3_AUX
J 1
(-1600 300);
DISPLAY 0.872340 (-1600 300);
PAINT GREEN (-1600 300);
FORCEPROP 2 LAST CDS_LIB pure_quanta_power
J 0
(-1600 250);
PAINT MONO (-1600 250);
DISPLAY INVISIBLE (-1600 250);
FORCEPROP 1 LAST PATH I19
J 0
(-1550 275);
DISPLAY 0.872340 (-1550 275);
PAINT AQUA (-1550 275);
DISPLAY INVISIBLE (-1550 275);
FORCEADD OFFPAGE..5
(-1175 600);
FORCEPROP 2 LAST $XR0 137 
J 0
(-1430 600);
DISPLAY 0.638298 (-1430 600);
PAINT MONO (-1430 600);
FORCEPROP 2 LAST CDS_LIB standard
J 0
(-1175 600);
PAINT MONO (-1175 600);
DISPLAY INVISIBLE (-1175 600);
FORCEPROP 1 LAST OFFPAGE TRUE
J 0
(-850 475);
DISPLAY 0.872340 (-850 475);
PAINT GREEN (-850 475);
DISPLAY INVISIBLE (-850 475);
FORCEPROP 1 LAST COMMENT_BODY TRUE
J 0
(-1075 525);
DISPLAY 0.872340 (-1075 525);
PAINT GREEN (-1075 525);
DISPLAY INVISIBLE (-1075 525);
FORCEPROP 2 LAST PATH I20
J 0
(-1425 650);
DISPLAY 1.021277 (-1425 650);
DISPLAY INVISIBLE (-1425 650);
FORCEADD OFFPAGE..5
(-1175 750);
FORCEPROP 2 LAST $XR0 137 
J 0
(-1430 750);
DISPLAY 0.638298 (-1430 750);
PAINT MONO (-1430 750);
FORCEPROP 2 LAST CDS_LIB standard
J 0
(-1175 750);
PAINT MONO (-1175 750);
DISPLAY INVISIBLE (-1175 750);
FORCEPROP 1 LAST OFFPAGE TRUE
J 0
(-850 625);
DISPLAY 0.872340 (-850 625);
PAINT GREEN (-850 625);
DISPLAY INVISIBLE (-850 625);
FORCEPROP 1 LAST COMMENT_BODY TRUE
J 0
(-1075 675);
DISPLAY 0.872340 (-1075 675);
PAINT GREEN (-1075 675);
DISPLAY INVISIBLE (-1075 675);
FORCEPROP 2 LAST PATH I21
J 0
(-1425 800);
DISPLAY 1.021277 (-1425 800);
DISPLAY INVISIBLE (-1425 800);
FORCEADD OFFPAGE..5
(-1175 900);
FORCEPROP 2 LAST $XR0 137 
J 0
(-1430 900);
DISPLAY 0.638298 (-1430 900);
PAINT MONO (-1430 900);
FORCEPROP 2 LAST CDS_LIB standard
J 0
(-1175 900);
PAINT MONO (-1175 900);
DISPLAY INVISIBLE (-1175 900);
FORCEPROP 1 LAST OFFPAGE TRUE
J 0
(-850 775);
DISPLAY 0.872340 (-850 775);
PAINT GREEN (-850 775);
DISPLAY INVISIBLE (-850 775);
FORCEPROP 1 LAST COMMENT_BODY TRUE
J 0
(-1075 825);
DISPLAY 0.872340 (-1075 825);
PAINT GREEN (-1075 825);
DISPLAY INVISIBLE (-1075 825);
FORCEPROP 2 LAST PATH I22
J 0
(-1425 950);
DISPLAY 1.021277 (-1425 950);
DISPLAY INVISIBLE (-1425 950);
FORCEADD OFFPAGE..5
(-1175 1050);
FORCEPROP 2 LAST $XR0 137 
J 0
(-1430 1050);
DISPLAY 0.638298 (-1430 1050);
PAINT MONO (-1430 1050);
FORCEPROP 2 LAST CDS_LIB standard
J 0
(-1175 1050);
PAINT MONO (-1175 1050);
DISPLAY INVISIBLE (-1175 1050);
FORCEPROP 1 LAST OFFPAGE TRUE
J 0
(-850 925);
DISPLAY 0.872340 (-850 925);
PAINT GREEN (-850 925);
DISPLAY INVISIBLE (-850 925);
FORCEPROP 1 LAST COMMENT_BODY TRUE
J 0
(-1075 975);
DISPLAY 0.872340 (-1075 975);
PAINT GREEN (-1075 975);
DISPLAY INVISIBLE (-1075 975);
FORCEPROP 2 LAST PATH I23
J 0
(-1425 1100);
DISPLAY 1.021277 (-1425 1100);
DISPLAY INVISIBLE (-1425 1100);
FORCEADD UNIVERSAL_GND..1
(-325 425);
FORCEPROP 3 LASTPIN (-325 475) SIG_NAME GND\g
J 0
(-315 485);
DISPLAY 0.659574 (-315 485);
PAINT MONO (-315 485);
DISPLAY INVISIBLE (-315 485);
FORCEPROP 2 LAST CDS_LIB pure_quanta_power
J 0
(-325 425);
PAINT MONO (-325 425);
DISPLAY INVISIBLE (-325 425);
FORCEPROP 1 LAST HDL_POWER GND
J 1
(-300 350);
DISPLAY 0.872340 (-300 350);
PAINT GREEN (-300 350);
DISPLAY INVISIBLE (-300 350);
FORCEPROP 1 LAST PATH I24
J 0
(-250 425);
DISPLAY 0.872340 (-250 425);
PAINT AQUA (-250 425);
DISPLAY INVISIBLE (-250 425);
FORCEADD UNIVERSAL_GND..1
(-525 1150);
FORCEPROP 3 LASTPIN (-525 1200) SIG_NAME GND\g
J 0
(-515 1210);
DISPLAY 0.659574 (-515 1210);
PAINT MONO (-515 1210);
DISPLAY INVISIBLE (-515 1210);
FORCEPROP 2 LAST CDS_LIB pure_quanta_power
J 0
(-525 1150);
PAINT MONO (-525 1150);
DISPLAY INVISIBLE (-525 1150);
FORCEPROP 1 LAST HDL_POWER GND
J 1
(-500 1075);
DISPLAY 0.872340 (-500 1075);
PAINT GREEN (-500 1075);
DISPLAY INVISIBLE (-500 1075);
FORCEPROP 1 LAST PATH I25
J 0
(-450 1150);
DISPLAY 0.872340 (-450 1150);
PAINT AQUA (-450 1150);
DISPLAY INVISIBLE (-450 1150);
FORCEADD UNIVERSAL_POWER..1
(-325 1700);
FORCEPROP 3 LASTPIN (-325 1650) SIG_NAME P3V3_AUX\g
J 0
(-315 1660);
DISPLAY 0.659574 (-315 1660);
PAINT MONO (-315 1660);
DISPLAY INVISIBLE (-315 1660);
FORCEPROP 1 LAST HDL_POWER P3V3_AUX
J 1
(-325 1750);
DISPLAY 0.872340 (-325 1750);
PAINT GREEN (-325 1750);
FORCEPROP 2 LAST CDS_LIB pure_quanta_power
J 0
(-325 1700);
PAINT MONO (-325 1700);
DISPLAY INVISIBLE (-325 1700);
FORCEPROP 1 LAST PATH I26
J 0
(-275 1725);
DISPLAY 0.872340 (-275 1725);
PAINT AQUA (-275 1725);
DISPLAY INVISIBLE (-275 1725);
FORCEADD OFFPAGE..1
(-1175 2175);
FORCEPROP 2 LAST $XR0 137 
J 0
(-1457 2175);
DISPLAY 0.638298 (-1457 2175);
PAINT MONO (-1457 2175);
FORCEPROP 2 LAST CDS_LIB standard
J 0
(-1175 2175);
PAINT MONO (-1175 2175);
DISPLAY INVISIBLE (-1175 2175);
FORCEPROP 1 LAST OFFPAGE TRUE
J 0
(-850 2050);
DISPLAY 0.872340 (-850 2050);
PAINT GREEN (-850 2050);
DISPLAY INVISIBLE (-850 2050);
FORCEPROP 1 LAST COMMENT_BODY TRUE
J 0
(-1050 2075);
DISPLAY 0.872340 (-1050 2075);
PAINT GREEN (-1050 2075);
DISPLAY INVISIBLE (-1050 2075);
FORCEPROP 2 LAST PATH I27
J 0
(-1450 2225);
DISPLAY 1.021277 (-1450 2225);
DISPLAY INVISIBLE (-1450 2225);
FORCEADD OFFPAGE..1
(-1175 2025);
FORCEPROP 2 LAST $XR0 137 
J 0
(-1457 2025);
DISPLAY 0.638298 (-1457 2025);
PAINT MONO (-1457 2025);
FORCEPROP 2 LAST CDS_LIB standard
J 0
(-1175 2025);
PAINT MONO (-1175 2025);
DISPLAY INVISIBLE (-1175 2025);
FORCEPROP 1 LAST OFFPAGE TRUE
J 0
(-850 1900);
DISPLAY 0.872340 (-850 1900);
PAINT GREEN (-850 1900);
DISPLAY INVISIBLE (-850 1900);
FORCEPROP 1 LAST COMMENT_BODY TRUE
J 0
(-1050 1925);
DISPLAY 0.872340 (-1050 1925);
PAINT GREEN (-1050 1925);
DISPLAY INVISIBLE (-1050 1925);
FORCEPROP 2 LAST PATH I28
J 0
(-1450 2075);
DISPLAY 1.021277 (-1450 2075);
DISPLAY INVISIBLE (-1450 2075);
FORCEADD OFFPAGE..1
(-1175 2325);
FORCEPROP 2 LAST $XR0 137 
J 0
(-1457 2325);
DISPLAY 0.638298 (-1457 2325);
PAINT MONO (-1457 2325);
FORCEPROP 2 LAST CDS_LIB standard
J 0
(-1175 2325);
PAINT MONO (-1175 2325);
DISPLAY INVISIBLE (-1175 2325);
FORCEPROP 1 LAST OFFPAGE TRUE
J 0
(-850 2200);
DISPLAY 0.872340 (-850 2200);
PAINT GREEN (-850 2200);
DISPLAY INVISIBLE (-850 2200);
FORCEPROP 1 LAST COMMENT_BODY TRUE
J 0
(-1050 2225);
DISPLAY 0.872340 (-1050 2225);
PAINT GREEN (-1050 2225);
DISPLAY INVISIBLE (-1050 2225);
FORCEPROP 2 LAST PATH I29
J 0
(-1450 2375);
DISPLAY 1.021277 (-1450 2375);
DISPLAY INVISIBLE (-1450 2375);
FORCEADD OFFPAGE..1
(-2550 -375);
FORCEPROP 2 LAST $XR1 80 
J 0
(-2892 -375);
DISPLAY 0.638298 (-2892 -375);
PAINT MONO (-2892 -375);
FORCEPROP 2 LAST $XR0 137 
J 0
(-2802 -375);
DISPLAY 0.638298 (-2802 -375);
PAINT MONO (-2802 -375);
FORCEPROP 2 LAST CDS_LIB standard
J 0
(-2550 -375);
PAINT MONO (-2550 -375);
DISPLAY INVISIBLE (-2550 -375);
FORCEPROP 1 LAST OFFPAGE TRUE
J 0
(-2225 -500);
DISPLAY 0.872340 (-2225 -500);
PAINT GREEN (-2225 -500);
DISPLAY INVISIBLE (-2225 -500);
FORCEPROP 1 LAST COMMENT_BODY TRUE
J 0
(-2425 -475);
DISPLAY 0.872340 (-2425 -475);
PAINT GREEN (-2425 -475);
DISPLAY INVISIBLE (-2425 -475);
FORCEPROP 2 LAST PATH I3
J 0
(-2800 -325);
DISPLAY 1.021277 (-2800 -325);
DISPLAY INVISIBLE (-2800 -325);
FORCEADD OFFPAGE..1
(-1175 2475);
FORCEPROP 2 LAST $XR0 137 
J 0
(-1457 2475);
DISPLAY 0.638298 (-1457 2475);
PAINT MONO (-1457 2475);
FORCEPROP 2 LAST CDS_LIB standard
J 0
(-1175 2475);
PAINT MONO (-1175 2475);
DISPLAY INVISIBLE (-1175 2475);
FORCEPROP 1 LAST OFFPAGE TRUE
J 0
(-850 2350);
DISPLAY 0.872340 (-850 2350);
PAINT GREEN (-850 2350);
DISPLAY INVISIBLE (-850 2350);
FORCEPROP 1 LAST COMMENT_BODY TRUE
J 0
(-1050 2375);
DISPLAY 0.872340 (-1050 2375);
PAINT GREEN (-1050 2375);
DISPLAY INVISIBLE (-1050 2375);
FORCEPROP 2 LAST PATH I30
J 0
(-1450 2525);
DISPLAY 1.021277 (-1450 2525);
DISPLAY INVISIBLE (-1450 2525);
FORCEADD UNIVERSAL_GND..1
(-325 1850);
FORCEPROP 3 LASTPIN (-325 1900) SIG_NAME GND\g
J 0
(-315 1910);
DISPLAY 0.659574 (-315 1910);
PAINT MONO (-315 1910);
DISPLAY INVISIBLE (-315 1910);
FORCEPROP 2 LAST CDS_LIB pure_quanta_power
J 0
(-325 1850);
PAINT MONO (-325 1850);
DISPLAY INVISIBLE (-325 1850);
FORCEPROP 1 LAST HDL_POWER GND
J 1
(-300 1775);
DISPLAY 0.872340 (-300 1775);
PAINT GREEN (-300 1775);
DISPLAY INVISIBLE (-300 1775);
FORCEPROP 1 LAST PATH I31
J 0
(-250 1850);
DISPLAY 0.872340 (-250 1850);
PAINT AQUA (-250 1850);
DISPLAY INVISIBLE (-250 1850);
FORCEADD 74CBTLV3126PW..1
R 2
(225 2275);
FORCEPROP 1 LAST LOCATION U222
J 2
(473 2733);
DISPLAY 0.723404 (473 2733);
PAINT GREEN (473 2733);
FORCEPROP 2 LAST $SEC 1
J 0
(450 2875);
DISPLAY 0.680851 (450 2875);
PAINT MONO (450 2875);
DISPLAY INVISIBLE (450 2875);
FORCEPROP 2 LAST CDS_SEC 1
J 0
(450 2875);
DISPLAY 1.021277 (450 2875);
DISPLAY INVISIBLE (450 2875);
FORCEPROP 2 LASTPIN (625 2025) $PN 2
J 0
(635 2035);
DISPLAY 0.808511 (635 2035);
FORCEPROP 2 LASTPIN (-175 2025) $PN 3
J 2
(-185 2035);
DISPLAY 0.808511 (-185 2035);
FORCEPROP 2 LASTPIN (625 1975) $PN 1
J 0
(635 1985);
DISPLAY 0.808511 (635 1985);
FORCEPROP 2 LASTPIN (625 2175) $PN 5
J 0
(635 2185);
DISPLAY 0.808511 (635 2185);
FORCEPROP 2 LASTPIN (-175 2175) $PN 6
J 2
(-185 2185);
DISPLAY 0.808511 (-185 2185);
FORCEPROP 2 LASTPIN (625 2125) $PN 4
J 0
(635 2135);
DISPLAY 0.808511 (635 2135);
FORCEPROP 2 LASTPIN (625 2325) $PN 9
J 0
(635 2335);
DISPLAY 0.808511 (635 2335);
FORCEPROP 2 LASTPIN (-175 2325) $PN 8
J 2
(-185 2335);
DISPLAY 0.808511 (-185 2335);
FORCEPROP 2 LASTPIN (625 2275) $PN 10
J 0
(635 2285);
DISPLAY 0.808511 (635 2285);
FORCEPROP 2 LASTPIN (625 2475) $PN 12
J 0
(635 2485);
DISPLAY 0.808511 (635 2485);
FORCEPROP 2 LASTPIN (-175 2475) $PN 11
J 2
(-185 2485);
DISPLAY 0.808511 (-185 2485);
FORCEPROP 2 LASTPIN (625 2425) $PN 13
J 0
(635 2435);
DISPLAY 0.808511 (635 2435);
FORCEPROP 2 LASTPIN (-175 1975) $PN 7
J 2
(-185 1985);
DISPLAY 0.808511 (-185 1985);
FORCEPROP 2 LASTPIN (-175 2525) $PN 14
J 2
(-185 2535);
DISPLAY 0.808511 (-185 2535);
FORCEPROP 2 LAST VALUE 74CBTLV3126PW
J 2
(450 2775);
DISPLAY 1.021277 (450 2775);
FORCEPROP 2 LAST PART_TYPE SMLF
J 2
(450 2825);
DISPLAY 1.021277 (450 2825);
FORCEPROP 1 LAST MATERIAL IC
J 2
(473 2628);
DISPLAY 0.723404 (473 2628);
PAINT GREEN (473 2628);
FORCEPROP 2 LAST CDS_LIB pure_quanta
J 2
(225 2275);
PAINT MONO (225 2275);
DISPLAY INVISIBLE (225 2275);
FORCEPROP 1 LAST NEEDS_NO_SIZE TRUE
J 2
(-25 1965);
DISPLAY 0.723404 (-25 1965);
PAINT GREEN (-25 1965);
DISPLAY INVISIBLE (-25 1965);
FORCEPROP 1 LAST CDS_LMAN_SYM_OUTLINE -250,350,250,-350
J 2
(225 2275);
DISPLAY 0.468085 (225 2275);
PAINT GREEN (225 2275);
DISPLAY INVISIBLE (225 2275);
FORCEPROP 1 LAST PATH I32
J 2
(-25 1925);
DISPLAY 0.723404 (-25 1925);
PAINT GREEN (-25 1925);
DISPLAY INVISIBLE (-25 1925);
FORCEPROP 1 LAST PART_NUMBER AL003126K08
J 2
(473 2683);
DISPLAY 0.723404 (473 2683);
PAINT GREEN (473 2683);
DISPLAY INVISIBLE (473 2683);
FORCEADD Q_CAP..1
R 2
(-525 2800);
FORCEPROP 1 LAST LOCATION C1826
J 2
(-575 2900);
DISPLAY 0.978723 (-575 2900);
FORCEPROP 2 LAST $SEC 1
J 0
(-575 3000);
DISPLAY 0.680851 (-575 3000);
PAINT MONO (-575 3000);
DISPLAY INVISIBLE (-575 3000);
FORCEPROP 2 LAST CDS_SEC 1
J 0
(-575 3000);
DISPLAY 1.021277 (-575 3000);
DISPLAY INVISIBLE (-575 3000);
FORCEPROP 1 LASTPIN (-525 2900) $PN 1
J 2
(-535 2880);
DISPLAY 0.787234 (-535 2880);
FORCEPROP 1 LASTPIN (-525 2700) $PN 2
J 2
(-535 2680);
DISPLAY 0.787234 (-535 2680);
FORCEPROP 1 LAST TOLERANCE 10%
J 2
(-575 2750);
DISPLAY 0.510638 (-575 2750);
FORCEPROP 1 LAST MATERIAL X7R
J 2
(-575 2700);
DISPLAY 0.510638 (-575 2700);
FORCEPROP 1 LAST VOLTAGE 25V
J 2
(-575 2800);
DISPLAY 0.510638 (-575 2800);
FORCEPROP 1 LAST VALUE 0.1UF
J 2
(-575 2850);
DISPLAY 0.510638 (-575 2850);
FORCEPROP 1 LAST PACK_TYPE 0402
J 2
(-575 2600);
DISPLAY 0.510638 (-575 2600);
FORCEPROP 2 LAST CDS_LIB pure_quanta
J 0
(-525 2800);
PAINT MONO (-525 2800);
DISPLAY INVISIBLE (-525 2800);
FORCEPROP 1 LAST PATH I33
J 2
(-575 2950);
DISPLAY 0.978723 (-575 2950);
PAINT WHITE (-575 2950);
DISPLAY INVISIBLE (-575 2950);
FORCEPROP 1 LAST PART_NUMBER CH4104K1B00
J 2
(-575 2650);
DISPLAY 0.510638 (-575 2650);
DISPLAY INVISIBLE (-575 2650);
FORCEADD UNIVERSAL_GND..1
(-525 2575);
FORCEPROP 3 LASTPIN (-525 2625) SIG_NAME GND\g
J 0
(-515 2635);
DISPLAY 0.659574 (-515 2635);
PAINT MONO (-515 2635);
DISPLAY INVISIBLE (-515 2635);
FORCEPROP 2 LAST CDS_LIB pure_quanta_power
J 0
(-525 2575);
PAINT MONO (-525 2575);
DISPLAY INVISIBLE (-525 2575);
FORCEPROP 1 LAST HDL_POWER GND
J 1
(-500 2500);
DISPLAY 0.872340 (-500 2500);
PAINT GREEN (-500 2500);
DISPLAY INVISIBLE (-500 2500);
FORCEPROP 1 LAST PATH I34
J 0
(-450 2575);
DISPLAY 0.872340 (-450 2575);
PAINT AQUA (-450 2575);
DISPLAY INVISIBLE (-450 2575);
FORCEADD UNIVERSAL_POWER..1
(-325 3125);
FORCEPROP 3 LASTPIN (-325 3075) SIG_NAME P3V3_AUX\g
J 0
(-315 3085);
DISPLAY 0.659574 (-315 3085);
PAINT MONO (-315 3085);
DISPLAY INVISIBLE (-315 3085);
FORCEPROP 1 LAST HDL_POWER P3V3_AUX
J 1
(-325 3175);
DISPLAY 0.872340 (-325 3175);
PAINT GREEN (-325 3175);
FORCEPROP 2 LAST CDS_LIB pure_quanta_power
J 0
(-325 3125);
PAINT MONO (-325 3125);
DISPLAY INVISIBLE (-325 3125);
FORCEPROP 1 LAST PATH I35
J 0
(-275 3150);
DISPLAY 0.872340 (-275 3150);
PAINT AQUA (-275 3150);
DISPLAY INVISIBLE (-275 3150);
FORCEADD Q_RES..2
(1800 -2525);
FORCEPROP 1 LAST LOCATION R3208
J 0
(1845 -2400);
DISPLAY 0.638298 (1845 -2400);
FORCEPROP 0 LAST $SEC 1
J 0
(1850 -2350);
DISPLAY 0.680851 (1850 -2350);
PAINT MONO (1850 -2350);
DISPLAY INVISIBLE (1850 -2350);
FORCEPROP 0 LAST CDS_SEC 1
J 0
(1850 -2350);
DISPLAY 1.021277 (1850 -2350);
DISPLAY INVISIBLE (1850 -2350);
FORCEPROP 1 LASTPIN (1800 -2425) $PN 1
J 0
(1805 -2463);
DISPLAY 0.787234 (1805 -2463);
PAINT MONO (1805 -2463);
FORCEPROP 1 LASTPIN (1800 -2625) $PN 2
J 0
(1805 -2615);
DISPLAY 0.787234 (1805 -2615);
PAINT MONO (1805 -2615);
FORCEPROP 1 LAST MATERIAL CHIP
J 0
(1840 -2600);
DISPLAY 0.638298 (1840 -2600);
FORCEPROP 1 LAST PACK_TYPE 0402LF
J 0
(1850 -2650);
DISPLAY 0.638298 (1850 -2650);
FORCEPROP 1 LAST WATTAGE 1/16W
J 0
(1840 -2550);
DISPLAY 0.638298 (1840 -2550);
FORCEPROP 1 LAST TOLERANCE 1%
J 0
(1845 -2500);
DISPLAY 0.638298 (1845 -2500);
FORCEPROP 1 LAST VALUE 100
J 0
(1845 -2450);
DISPLAY 0.638298 (1845 -2450);
FORCEPROP 2 LAST CDS_LIB pure_quanta
J 0
(1800 -2525);
DISPLAY INVISIBLE (1800 -2525);
FORCEPROP 1 LAST PATH I37
J 0
(1850 -2350);
DISPLAY 0.978723 (1850 -2350);
PAINT WHITE (1850 -2350);
DISPLAY INVISIBLE (1850 -2350);
FORCEPROP 1 LAST PART_NUMBER CS11002FB07
J 0
(1840 -2650);
DISPLAY 0.638298 (1840 -2650);
DISPLAY INVISIBLE (1840 -2650);
FORCEADD Q_RES..2
(2050 -2525);
FORCEPROP 1 LAST LOCATION R3216
J 0
(2095 -2400);
DISPLAY 0.638298 (2095 -2400);
FORCEPROP 0 LAST $SEC 1
J 0
(2100 -2350);
DISPLAY 0.680851 (2100 -2350);
PAINT MONO (2100 -2350);
DISPLAY INVISIBLE (2100 -2350);
FORCEPROP 0 LAST CDS_SEC 1
J 0
(2100 -2350);
DISPLAY 1.021277 (2100 -2350);
DISPLAY INVISIBLE (2100 -2350);
FORCEPROP 1 LASTPIN (2050 -2425) $PN 1
J 0
(2055 -2463);
DISPLAY 0.787234 (2055 -2463);
PAINT MONO (2055 -2463);
FORCEPROP 1 LASTPIN (2050 -2625) $PN 2
J 0
(2055 -2615);
DISPLAY 0.787234 (2055 -2615);
PAINT MONO (2055 -2615);
FORCEPROP 1 LAST PACK_TYPE 0402LF
J 0
(2100 -2650);
DISPLAY 0.638298 (2100 -2650);
FORCEPROP 1 LAST WATTAGE 1/16W
J 0
(2090 -2550);
DISPLAY 0.638298 (2090 -2550);
FORCEPROP 1 LAST TOLERANCE 1%
J 0
(2095 -2500);
DISPLAY 0.638298 (2095 -2500);
FORCEPROP 1 LAST VALUE 100
J 0
(2095 -2450);
DISPLAY 0.638298 (2095 -2450);
FORCEPROP 1 LAST MATERIAL CHIP
J 0
(2090 -2600);
DISPLAY 0.638298 (2090 -2600);
FORCEPROP 2 LAST CDS_LIB pure_quanta
J 0
(2050 -2525);
DISPLAY INVISIBLE (2050 -2525);
FORCEPROP 1 LAST PATH I38
J 0
(2100 -2350);
DISPLAY 0.978723 (2100 -2350);
PAINT WHITE (2100 -2350);
DISPLAY INVISIBLE (2100 -2350);
FORCEPROP 1 LAST PART_NUMBER CS11002FB07
J 0
(2090 -2650);
DISPLAY 0.638298 (2090 -2650);
DISPLAY INVISIBLE (2090 -2650);
FORCEADD UNIVERSAL_GND..1
(1800 -2800);
FORCEPROP 3 LASTPIN (1800 -2750) SIG_NAME GND\g
J 0
(1810 -2740);
DISPLAY 0.659574 (1810 -2740);
PAINT MONO (1810 -2740);
DISPLAY INVISIBLE (1810 -2740);
FORCEPROP 2 LAST CDS_LIB pure_quanta_power
J 0
(1800 -2800);
DISPLAY INVISIBLE (1800 -2800);
FORCEPROP 1 LAST HDL_POWER GND
J 1
(1825 -2875);
DISPLAY 0.872340 (1825 -2875);
PAINT GREEN (1825 -2875);
DISPLAY INVISIBLE (1825 -2875);
FORCEPROP 1 LAST PATH I39
J 0
(1875 -2800);
DISPLAY 0.872340 (1875 -2800);
PAINT AQUA (1875 -2800);
DISPLAY INVISIBLE (1875 -2800);
FORCEADD Q_RES..2
(2300 -2525);
FORCEPROP 1 LAST LOCATION R3217
J 0
(2345 -2400);
DISPLAY 0.638298 (2345 -2400);
FORCEPROP 0 LAST $SEC 1
J 0
(2350 -2350);
DISPLAY 0.680851 (2350 -2350);
PAINT MONO (2350 -2350);
DISPLAY INVISIBLE (2350 -2350);
FORCEPROP 0 LAST CDS_SEC 1
J 0
(2350 -2350);
DISPLAY 1.021277 (2350 -2350);
DISPLAY INVISIBLE (2350 -2350);
FORCEPROP 1 LASTPIN (2300 -2425) $PN 1
J 0
(2305 -2463);
DISPLAY 0.787234 (2305 -2463);
PAINT MONO (2305 -2463);
FORCEPROP 1 LASTPIN (2300 -2625) $PN 2
J 0
(2305 -2615);
DISPLAY 0.787234 (2305 -2615);
PAINT MONO (2305 -2615);
FORCEPROP 1 LAST PACK_TYPE 0402LF
J 0
(2340 -2700);
DISPLAY 0.638298 (2340 -2700);
FORCEPROP 1 LAST WATTAGE 1/16W
J 0
(2340 -2550);
DISPLAY 0.638298 (2340 -2550);
FORCEPROP 1 LAST MATERIAL CHIP
J 0
(2340 -2600);
DISPLAY 0.638298 (2340 -2600);
FORCEPROP 1 LAST VALUE 100
J 0
(2345 -2450);
DISPLAY 0.638298 (2345 -2450);
FORCEPROP 1 LAST TOLERANCE 1%
J 0
(2345 -2500);
DISPLAY 0.638298 (2345 -2500);
FORCEPROP 2 LAST CDS_LIB pure_quanta
J 0
(2300 -2525);
DISPLAY INVISIBLE (2300 -2525);
FORCEPROP 1 LAST PATH I40
J 0
(2350 -2350);
DISPLAY 0.978723 (2350 -2350);
PAINT WHITE (2350 -2350);
DISPLAY INVISIBLE (2350 -2350);
FORCEPROP 1 LAST PART_NUMBER CS11002FB07
J 0
(2340 -2650);
DISPLAY 0.638298 (2340 -2650);
DISPLAY INVISIBLE (2340 -2650);
FORCEADD OFFPAGE..2
(3325 -2275);
FORCEPROP 2 LAST $XR0 137 
J 0
(3514 -2275);
DISPLAY 0.638298 (3514 -2275);
PAINT MONO (3514 -2275);
FORCEPROP 2 LAST CDS_LIB standard
J 0
(3325 -2275);
PAINT MONO (3325 -2275);
DISPLAY INVISIBLE (3325 -2275);
FORCEPROP 1 LAST OFFPAGE TRUE
J 0
(3650 -2400);
DISPLAY 0.872340 (3650 -2400);
PAINT GREEN (3650 -2400);
DISPLAY INVISIBLE (3650 -2400);
FORCEPROP 1 LAST COMMENT_BODY TRUE
J 0
(3280 -2370);
DISPLAY 0.872340 (3280 -2370);
PAINT GREEN (3280 -2370);
DISPLAY INVISIBLE (3280 -2370);
FORCEPROP 2 LAST PATH I44
J 0
(3525 -2225);
DISPLAY 1.021277 (3525 -2225);
DISPLAY INVISIBLE (3525 -2225);
FORCEADD OFFPAGE..2
(3325 -2125);
FORCEPROP 2 LAST $XR0 137 
J 0
(3514 -2125);
DISPLAY 0.638298 (3514 -2125);
PAINT MONO (3514 -2125);
FORCEPROP 2 LAST CDS_LIB standard
J 0
(3325 -2125);
PAINT MONO (3325 -2125);
DISPLAY INVISIBLE (3325 -2125);
FORCEPROP 1 LAST OFFPAGE TRUE
J 0
(3650 -2250);
DISPLAY 0.872340 (3650 -2250);
PAINT GREEN (3650 -2250);
DISPLAY INVISIBLE (3650 -2250);
FORCEPROP 1 LAST COMMENT_BODY TRUE
J 0
(3280 -2220);
DISPLAY 0.872340 (3280 -2220);
PAINT GREEN (3280 -2220);
DISPLAY INVISIBLE (3280 -2220);
FORCEPROP 2 LAST PATH I45
J 0
(3525 -2075);
DISPLAY 1.021277 (3525 -2075);
DISPLAY INVISIBLE (3525 -2075);
FORCEADD OFFPAGE..2
(3325 -1975);
FORCEPROP 2 LAST $XR0 137 
J 0
(3514 -1975);
DISPLAY 0.638298 (3514 -1975);
PAINT MONO (3514 -1975);
FORCEPROP 2 LAST CDS_LIB standard
J 0
(3325 -1975);
PAINT MONO (3325 -1975);
DISPLAY INVISIBLE (3325 -1975);
FORCEPROP 1 LAST OFFPAGE TRUE
J 0
(3650 -2100);
DISPLAY 0.872340 (3650 -2100);
PAINT GREEN (3650 -2100);
DISPLAY INVISIBLE (3650 -2100);
FORCEPROP 1 LAST COMMENT_BODY TRUE
J 0
(3280 -2070);
DISPLAY 0.872340 (3280 -2070);
PAINT GREEN (3280 -2070);
DISPLAY INVISIBLE (3280 -2070);
FORCEPROP 2 LAST PATH I46
J 0
(3525 -1925);
DISPLAY 1.021277 (3525 -1925);
DISPLAY INVISIBLE (3525 -1925);
FORCEADD Q_RES..1
(1900 600);
FORCEPROP 1 LAST LOCATION R3215
J 0
(1600 600);
DISPLAY 0.702128 (1600 600);
FORCEPROP 0 LAST $SEC 1
J 0
(1975 650);
DISPLAY INVISIBLE (1975 650);
FORCEPROP 0 LAST CDS_SEC 1
J 0
(1975 650);
DISPLAY INVISIBLE (1975 650);
FORCEPROP 1 LASTPIN (1800 600) $PN 1
J 0
(1812 612);
DISPLAY 0.808511 (1812 612);
PAINT WHITE (1812 612);
DISPLAY INVISIBLE (1812 612);
FORCEPROP 1 LASTPIN (2000 600) $PN 2
J 0
(1962 612);
DISPLAY 0.808511 (1962 612);
PAINT WHITE (1962 612);
DISPLAY INVISIBLE (1962 612);
FORCEPROP 1 LAST VALUE 0
J 2
(2050 600);
DISPLAY 0.638298 (2050 600);
FORCEPROP 1 LAST MATERIAL EMPTY
J 0
(2100 600);
DISPLAY 0.638298 (2100 600);
PAINT RED (2100 600);
FORCEPROP 2 LAST CDS_LIB pure_quanta
J 0
(1900 600);
DISPLAY INVISIBLE (1900 600);
FORCEPROP 1 LAST PACK_TYPE 0402LF
J 0
(2150 450);
DISPLAY 0.510638 (2150 450);
PAINT SKYBLUE (2150 450);
DISPLAY INVISIBLE (2150 450);
FORCEPROP 1 LAST WATTAGE 1/16W
J 2
(1875 450);
DISPLAY 0.510638 (1875 450);
PAINT SKYBLUE (1875 450);
DISPLAY INVISIBLE (1875 450);
FORCEPROP 1 LAST TOLERANCE 5%
J 0
(1900 500);
DISPLAY 0.510638 (1900 500);
PAINT SKYBLUE (1900 500);
DISPLAY INVISIBLE (1900 500);
FORCEPROP 1 LAST PATH I56
J 0
(1850 750);
DISPLAY 0.978723 (1850 750);
PAINT WHITE (1850 750);
DISPLAY INVISIBLE (1850 750);
FORCEPROP 1 LAST PART_NUMBER CS00002JB13
J 0
(1850 700);
DISPLAY 0.510638 (1850 700);
PAINT WHITE (1850 700);
DISPLAY INVISIBLE (1850 700);
FORCEADD Q_RES..1
(1900 750);
FORCEPROP 1 LAST LOCATION R3214
J 0
(1600 750);
DISPLAY 0.702128 (1600 750);
FORCEPROP 0 LAST $SEC 1
J 0
(1975 800);
DISPLAY INVISIBLE (1975 800);
FORCEPROP 0 LAST CDS_SEC 1
J 0
(1975 800);
DISPLAY INVISIBLE (1975 800);
FORCEPROP 1 LASTPIN (1800 750) $PN 1
J 0
(1812 762);
DISPLAY 0.808511 (1812 762);
PAINT WHITE (1812 762);
DISPLAY INVISIBLE (1812 762);
FORCEPROP 1 LASTPIN (2000 750) $PN 2
J 0
(1962 762);
DISPLAY 0.808511 (1962 762);
PAINT WHITE (1962 762);
DISPLAY INVISIBLE (1962 762);
FORCEPROP 1 LAST MATERIAL EMPTY
J 0
(2100 750);
DISPLAY 0.638298 (2100 750);
PAINT RED (2100 750);
FORCEPROP 1 LAST VALUE 0
J 2
(2050 750);
DISPLAY 0.638298 (2050 750);
FORCEPROP 2 LAST CDS_LIB pure_quanta
J 0
(1900 750);
DISPLAY INVISIBLE (1900 750);
FORCEPROP 1 LAST PACK_TYPE 0402LF
J 0
(2150 600);
DISPLAY 0.510638 (2150 600);
PAINT SKYBLUE (2150 600);
DISPLAY INVISIBLE (2150 600);
FORCEPROP 1 LAST WATTAGE 1/16W
J 2
(1875 600);
DISPLAY 0.510638 (1875 600);
PAINT SKYBLUE (1875 600);
DISPLAY INVISIBLE (1875 600);
FORCEPROP 1 LAST TOLERANCE 5%
J 0
(1900 650);
DISPLAY 0.510638 (1900 650);
PAINT SKYBLUE (1900 650);
DISPLAY INVISIBLE (1900 650);
FORCEPROP 1 LAST PATH I60
J 0
(1850 900);
DISPLAY 0.978723 (1850 900);
PAINT WHITE (1850 900);
DISPLAY INVISIBLE (1850 900);
FORCEPROP 1 LAST PART_NUMBER CS00002JB13
J 0
(1850 850);
DISPLAY 0.510638 (1850 850);
PAINT WHITE (1850 850);
DISPLAY INVISIBLE (1850 850);
FORCEADD Q_RES..1
(1900 900);
FORCEPROP 1 LAST LOCATION R3213
J 0
(1600 900);
DISPLAY 0.702128 (1600 900);
FORCEPROP 0 LAST $SEC 1
J 0
(1975 950);
DISPLAY INVISIBLE (1975 950);
FORCEPROP 0 LAST CDS_SEC 1
J 0
(1975 950);
DISPLAY INVISIBLE (1975 950);
FORCEPROP 1 LASTPIN (1800 900) $PN 1
J 0
(1812 912);
DISPLAY 0.808511 (1812 912);
PAINT WHITE (1812 912);
DISPLAY INVISIBLE (1812 912);
FORCEPROP 1 LASTPIN (2000 900) $PN 2
J 0
(1962 912);
DISPLAY 0.808511 (1962 912);
PAINT WHITE (1962 912);
DISPLAY INVISIBLE (1962 912);
FORCEPROP 1 LAST MATERIAL EMPTY
J 0
(2100 900);
DISPLAY 0.638298 (2100 900);
PAINT RED (2100 900);
FORCEPROP 1 LAST VALUE 0
J 2
(2050 900);
DISPLAY 0.638298 (2050 900);
FORCEPROP 2 LAST CDS_LIB pure_quanta
J 0
(1900 900);
DISPLAY INVISIBLE (1900 900);
FORCEPROP 1 LAST TOLERANCE 5%
J 0
(1900 800);
DISPLAY 0.510638 (1900 800);
PAINT SKYBLUE (1900 800);
DISPLAY INVISIBLE (1900 800);
FORCEPROP 1 LAST PACK_TYPE 0402LF
J 0
(2150 750);
DISPLAY 0.510638 (2150 750);
PAINT SKYBLUE (2150 750);
DISPLAY INVISIBLE (2150 750);
FORCEPROP 1 LAST WATTAGE 1/16W
J 2
(1875 750);
DISPLAY 0.510638 (1875 750);
PAINT SKYBLUE (1875 750);
DISPLAY INVISIBLE (1875 750);
FORCEPROP 1 LAST PATH I61
J 0
(1850 1050);
DISPLAY 0.978723 (1850 1050);
PAINT WHITE (1850 1050);
DISPLAY INVISIBLE (1850 1050);
FORCEPROP 1 LAST PART_NUMBER CS00002JB13
J 0
(1775 975);
DISPLAY 0.510638 (1775 975);
DISPLAY INVISIBLE (1775 975);
FORCEADD Q_RES..1
(1900 2025);
FORCEPROP 1 LAST LOCATION R3212
J 0
(1600 2025);
DISPLAY 0.702128 (1600 2025);
PAINT YELLOW (1600 2025);
FORCEPROP 0 LAST $SEC 1
J 0
(1975 2075);
DISPLAY INVISIBLE (1975 2075);
FORCEPROP 0 LAST CDS_SEC 1
J 0
(1975 2075);
DISPLAY INVISIBLE (1975 2075);
FORCEPROP 1 LASTPIN (1800 2025) $PN 1
J 0
(1812 2037);
DISPLAY 0.808511 (1812 2037);
PAINT WHITE (1812 2037);
DISPLAY INVISIBLE (1812 2037);
FORCEPROP 1 LASTPIN (2000 2025) $PN 2
J 0
(1962 2037);
DISPLAY 0.808511 (1962 2037);
PAINT WHITE (1962 2037);
DISPLAY INVISIBLE (1962 2037);
FORCEPROP 1 LAST MATERIAL EMPTY
J 0
(1975 2050);
DISPLAY 0.510638 (1975 2050);
PAINT RED (1975 2050);
FORCEPROP 1 LAST VALUE 22
J 2
(1850 2050);
DISPLAY 0.510638 (1850 2050);
PAINT SKYBLUE (1850 2050);
FORCEPROP 2 LAST CDS_LIB pure_quanta
J 0
(1900 2025);
DISPLAY INVISIBLE (1900 2025);
FORCEPROP 1 LAST PACK_TYPE 0402LF
J 0
(2150 1875);
DISPLAY 0.510638 (2150 1875);
PAINT SKYBLUE (2150 1875);
DISPLAY INVISIBLE (2150 1875);
FORCEPROP 1 LAST TOLERANCE 1%
J 0
(1900 1925);
DISPLAY 0.510638 (1900 1925);
PAINT SKYBLUE (1900 1925);
DISPLAY INVISIBLE (1900 1925);
FORCEPROP 1 LAST WATTAGE 1/16W
J 2
(1875 1875);
DISPLAY 0.510638 (1875 1875);
PAINT SKYBLUE (1875 1875);
DISPLAY INVISIBLE (1875 1875);
FORCEPROP 1 LAST PATH I62
J 0
(1850 2175);
DISPLAY 0.978723 (1850 2175);
PAINT WHITE (1850 2175);
DISPLAY INVISIBLE (1850 2175);
FORCEPROP 1 LAST PART_NUMBER CS02202FB02
J 0
(1850 2125);
DISPLAY 0.510638 (1850 2125);
PAINT WHITE (1850 2125);
DISPLAY INVISIBLE (1850 2125);
FORCEADD Q_RES..1
(1900 2175);
FORCEPROP 1 LAST LOCATION R3211
J 0
(1600 2175);
DISPLAY 0.702128 (1600 2175);
PAINT YELLOW (1600 2175);
FORCEPROP 0 LAST $SEC 1
J 0
(1975 2225);
DISPLAY INVISIBLE (1975 2225);
FORCEPROP 0 LAST CDS_SEC 1
J 0
(1975 2225);
DISPLAY INVISIBLE (1975 2225);
FORCEPROP 1 LASTPIN (1800 2175) $PN 1
J 0
(1812 2187);
DISPLAY 0.808511 (1812 2187);
PAINT WHITE (1812 2187);
DISPLAY INVISIBLE (1812 2187);
FORCEPROP 1 LASTPIN (2000 2175) $PN 2
J 0
(1962 2187);
DISPLAY 0.808511 (1962 2187);
PAINT WHITE (1962 2187);
DISPLAY INVISIBLE (1962 2187);
FORCEPROP 1 LAST MATERIAL EMPTY
J 0
(1975 2200);
DISPLAY 0.510638 (1975 2200);
PAINT RED (1975 2200);
FORCEPROP 1 LAST VALUE 22
J 2
(1850 2200);
DISPLAY 0.510638 (1850 2200);
PAINT SKYBLUE (1850 2200);
FORCEPROP 2 LAST CDS_LIB pure_quanta
J 0
(1900 2175);
DISPLAY INVISIBLE (1900 2175);
FORCEPROP 1 LAST PACK_TYPE 0402LF
J 0
(2150 2025);
DISPLAY 0.510638 (2150 2025);
PAINT SKYBLUE (2150 2025);
DISPLAY INVISIBLE (2150 2025);
FORCEPROP 1 LAST TOLERANCE 1%
J 0
(1900 2075);
DISPLAY 0.510638 (1900 2075);
PAINT SKYBLUE (1900 2075);
DISPLAY INVISIBLE (1900 2075);
FORCEPROP 1 LAST WATTAGE 1/16W
J 2
(1875 2025);
DISPLAY 0.510638 (1875 2025);
PAINT SKYBLUE (1875 2025);
DISPLAY INVISIBLE (1875 2025);
FORCEPROP 1 LAST PATH I63
J 0
(1850 2325);
DISPLAY 0.978723 (1850 2325);
PAINT WHITE (1850 2325);
DISPLAY INVISIBLE (1850 2325);
FORCEPROP 1 LAST PART_NUMBER CS02202FB02
J 0
(1850 2275);
DISPLAY 0.510638 (1850 2275);
PAINT WHITE (1850 2275);
DISPLAY INVISIBLE (1850 2275);
FORCEADD Q_RES..1
(3450 2475);
FORCEPROP 1 LAST LOCATION R3209
J 0
(3225 2475);
DISPLAY 0.702128 (3225 2475);
PAINT YELLOW (3225 2475);
FORCEPROP 0 LAST $SEC 1
J 0
(3525 2525);
DISPLAY INVISIBLE (3525 2525);
FORCEPROP 0 LAST CDS_SEC 1
J 0
(3525 2525);
DISPLAY INVISIBLE (3525 2525);
FORCEPROP 1 LASTPIN (3350 2475) $PN 1
J 0
(3362 2487);
DISPLAY 0.808511 (3362 2487);
PAINT WHITE (3362 2487);
DISPLAY INVISIBLE (3362 2487);
FORCEPROP 1 LASTPIN (3550 2475) $PN 2
J 0
(3512 2487);
DISPLAY 0.808511 (3512 2487);
PAINT WHITE (3512 2487);
DISPLAY INVISIBLE (3512 2487);
FORCEPROP 1 LAST MATERIAL EMPTY
J 0
(3525 2500);
DISPLAY 0.510638 (3525 2500);
PAINT RED (3525 2500);
FORCEPROP 1 LAST PACK_TYPE 0402LF
J 0
(3475 2575);
DISPLAY 0.510638 (3475 2575);
PAINT SKYBLUE (3475 2575);
FORCEPROP 1 LAST VALUE 22
J 2
(3400 2500);
DISPLAY 0.510638 (3400 2500);
PAINT SKYBLUE (3400 2500);
FORCEPROP 1 LAST WATTAGE 1/16W
J 2
(3450 2575);
DISPLAY 0.510638 (3450 2575);
PAINT SKYBLUE (3450 2575);
FORCEPROP 1 LAST TOLERANCE 1%
J 0
(3450 2375);
DISPLAY 0.510638 (3450 2375);
PAINT SKYBLUE (3450 2375);
DISPLAY INVISIBLE (3450 2375);
FORCEPROP 2 LAST CDS_LIB pure_quanta
J 0
(3450 2475);
DISPLAY INVISIBLE (3450 2475);
FORCEPROP 1 LAST PATH I64
J 0
(3400 2625);
DISPLAY 0.978723 (3400 2625);
PAINT WHITE (3400 2625);
DISPLAY INVISIBLE (3400 2625);
FORCEPROP 1 LAST PART_NUMBER CS02202FB02
J 0
(3350 2625);
DISPLAY 0.510638 (3350 2625);
PAINT WHITE (3350 2625);
DISPLAY INVISIBLE (3350 2625);
FORCEADD Q_RES..1
(1900 2325);
FORCEPROP 1 LAST LOCATION R3210
J 0
(1600 2325);
DISPLAY 0.702128 (1600 2325);
PAINT YELLOW (1600 2325);
FORCEPROP 0 LAST $SEC 1
J 0
(1975 2375);
DISPLAY INVISIBLE (1975 2375);
FORCEPROP 0 LAST CDS_SEC 1
J 0
(1975 2375);
DISPLAY INVISIBLE (1975 2375);
FORCEPROP 1 LASTPIN (1800 2325) $PN 1
J 0
(1812 2337);
DISPLAY 0.808511 (1812 2337);
PAINT WHITE (1812 2337);
DISPLAY INVISIBLE (1812 2337);
FORCEPROP 1 LASTPIN (2000 2325) $PN 2
J 0
(1962 2337);
DISPLAY 0.808511 (1962 2337);
PAINT WHITE (1962 2337);
DISPLAY INVISIBLE (1962 2337);
FORCEPROP 1 LAST MATERIAL EMPTY
J 0
(1975 2350);
DISPLAY 0.510638 (1975 2350);
PAINT RED (1975 2350);
FORCEPROP 1 LAST VALUE 22
J 2
(1850 2350);
DISPLAY 0.510638 (1850 2350);
PAINT SKYBLUE (1850 2350);
FORCEPROP 1 LAST WATTAGE 1/16W
J 2
(1875 2175);
DISPLAY 0.510638 (1875 2175);
PAINT SKYBLUE (1875 2175);
DISPLAY INVISIBLE (1875 2175);
FORCEPROP 1 LAST TOLERANCE 1%
J 0
(1900 2225);
DISPLAY 0.510638 (1900 2225);
PAINT SKYBLUE (1900 2225);
DISPLAY INVISIBLE (1900 2225);
FORCEPROP 1 LAST PACK_TYPE 0402LF
J 0
(2150 2175);
DISPLAY 0.510638 (2150 2175);
PAINT SKYBLUE (2150 2175);
DISPLAY INVISIBLE (2150 2175);
FORCEPROP 2 LAST CDS_LIB pure_quanta
J 0
(1900 2325);
DISPLAY INVISIBLE (1900 2325);
FORCEPROP 1 LAST PATH I65
J 0
(1850 2475);
DISPLAY 0.978723 (1850 2475);
PAINT WHITE (1850 2475);
DISPLAY INVISIBLE (1850 2475);
FORCEPROP 1 LAST PART_NUMBER CS02202FB02
J 0
(1850 2425);
DISPLAY 0.510638 (1850 2425);
PAINT WHITE (1850 2425);
DISPLAY INVISIBLE (1850 2425);
FORCEADD OFFPAGE..4
(2925 600);
FORCEPROP 2 LAST $XR1 150 
J 0
(3231 600);
DISPLAY 0.638298 (3231 600);
PAINT MONO (3231 600);
FORCEPROP 2 LAST $XR0 132 
J 0
(3111 600);
DISPLAY 0.638298 (3111 600);
PAINT MONO (3111 600);
FORCEPROP 2 LAST CDS_LIB standard
J 0
(2925 600);
PAINT MONO (2925 600);
DISPLAY INVISIBLE (2925 600);
FORCEPROP 1 LAST OFFPAGE TRUE
J 0
(3250 475);
DISPLAY 0.872340 (3250 475);
PAINT GREEN (3250 475);
DISPLAY INVISIBLE (3250 475);
FORCEPROP 1 LAST COMMENT_BODY TRUE
J 0
(2900 500);
DISPLAY 0.872340 (2900 500);
PAINT GREEN (2900 500);
DISPLAY INVISIBLE (2900 500);
FORCEPROP 2 LAST PATH I66
J 0
(3250 650);
DISPLAY 1.021277 (3250 650);
DISPLAY INVISIBLE (3250 650);
FORCEADD OFFPAGE..4
(2925 750);
FORCEPROP 2 LAST $XR1 150 
J 0
(3231 750);
DISPLAY 0.638298 (3231 750);
PAINT MONO (3231 750);
FORCEPROP 2 LAST $XR0 132 
J 0
(3111 750);
DISPLAY 0.638298 (3111 750);
PAINT MONO (3111 750);
FORCEPROP 2 LAST CDS_LIB standard
J 0
(2925 750);
PAINT MONO (2925 750);
DISPLAY INVISIBLE (2925 750);
FORCEPROP 1 LAST OFFPAGE TRUE
J 0
(3250 625);
DISPLAY 0.872340 (3250 625);
PAINT GREEN (3250 625);
DISPLAY INVISIBLE (3250 625);
FORCEPROP 1 LAST COMMENT_BODY TRUE
J 0
(2900 650);
DISPLAY 0.872340 (2900 650);
PAINT GREEN (2900 650);
DISPLAY INVISIBLE (2900 650);
FORCEPROP 2 LAST PATH I67
J 0
(3250 800);
DISPLAY 1.021277 (3250 800);
DISPLAY INVISIBLE (3250 800);
FORCEADD OFFPAGE..4
(2925 900);
FORCEPROP 2 LAST $XR1 150 
J 0
(3231 900);
DISPLAY 0.638298 (3231 900);
PAINT MONO (3231 900);
FORCEPROP 2 LAST $XR0 132 
J 0
(3111 900);
DISPLAY 0.638298 (3111 900);
PAINT MONO (3111 900);
FORCEPROP 2 LAST CDS_LIB standard
J 0
(2925 900);
PAINT MONO (2925 900);
DISPLAY INVISIBLE (2925 900);
FORCEPROP 1 LAST OFFPAGE TRUE
J 0
(3250 775);
DISPLAY 0.872340 (3250 775);
PAINT GREEN (3250 775);
DISPLAY INVISIBLE (3250 775);
FORCEPROP 1 LAST COMMENT_BODY TRUE
J 0
(2900 800);
DISPLAY 0.872340 (2900 800);
PAINT GREEN (2900 800);
DISPLAY INVISIBLE (2900 800);
FORCEPROP 2 LAST PATH I68
J 0
(3250 950);
DISPLAY 1.021277 (3250 950);
DISPLAY INVISIBLE (3250 950);
FORCEADD OFFPAGE..4
(4325 1050);
FORCEPROP 2 LAST $XR0 143 
J 0
(4511 1050);
DISPLAY 0.638298 (4511 1050);
PAINT MONO (4511 1050);
FORCEPROP 2 LAST CDS_LIB standard
J 0
(4325 1050);
PAINT MONO (4325 1050);
DISPLAY INVISIBLE (4325 1050);
FORCEPROP 1 LAST OFFPAGE TRUE
J 0
(4650 925);
DISPLAY 0.872340 (4650 925);
PAINT GREEN (4650 925);
DISPLAY INVISIBLE (4650 925);
FORCEPROP 1 LAST COMMENT_BODY TRUE
J 0
(4300 950);
DISPLAY 0.872340 (4300 950);
PAINT GREEN (4300 950);
DISPLAY INVISIBLE (4300 950);
FORCEPROP 2 LAST PATH I69
J 0
(4525 1100);
DISPLAY 1.021277 (4525 1100);
DISPLAY INVISIBLE (4525 1100);
FORCEADD OFFPAGE..2
(2800 2025);
FORCEPROP 2 LAST $XR1 150 
J 0
(3109 2025);
DISPLAY 0.638298 (3109 2025);
PAINT MONO (3109 2025);
FORCEPROP 2 LAST $XR0 132 
J 0
(2989 2025);
DISPLAY 0.638298 (2989 2025);
PAINT MONO (2989 2025);
FORCEPROP 2 LAST CDS_LIB standard
J 0
(2800 2025);
PAINT MONO (2800 2025);
DISPLAY INVISIBLE (2800 2025);
FORCEPROP 1 LAST OFFPAGE TRUE
J 0
(3125 1900);
DISPLAY 0.872340 (3125 1900);
PAINT GREEN (3125 1900);
DISPLAY INVISIBLE (3125 1900);
FORCEPROP 1 LAST COMMENT_BODY TRUE
J 0
(2755 1930);
DISPLAY 0.872340 (2755 1930);
PAINT GREEN (2755 1930);
DISPLAY INVISIBLE (2755 1930);
FORCEPROP 2 LAST PATH I73
J 0
(3125 2075);
DISPLAY 1.021277 (3125 2075);
DISPLAY INVISIBLE (3125 2075);
FORCEADD OFFPAGE..2
(2800 2175);
FORCEPROP 2 LAST $XR1 150 
J 0
(2989 2139);
DISPLAY 0.638298 (2989 2139);
PAINT MONO (2989 2139);
FORCEPROP 2 LAST $XR0 132 
J 0
(2989 2175);
DISPLAY 0.638298 (2989 2175);
PAINT MONO (2989 2175);
FORCEPROP 2 LAST CDS_LIB standard
J 0
(2800 2175);
PAINT MONO (2800 2175);
DISPLAY INVISIBLE (2800 2175);
FORCEPROP 1 LAST OFFPAGE TRUE
J 0
(3125 2050);
DISPLAY 0.872340 (3125 2050);
PAINT GREEN (3125 2050);
DISPLAY INVISIBLE (3125 2050);
FORCEPROP 1 LAST COMMENT_BODY TRUE
J 0
(2755 2080);
DISPLAY 0.872340 (2755 2080);
PAINT GREEN (2755 2080);
DISPLAY INVISIBLE (2755 2080);
FORCEPROP 2 LAST PATH I74
J 0
(3125 2225);
DISPLAY 1.021277 (3125 2225);
DISPLAY INVISIBLE (3125 2225);
FORCEADD OFFPAGE..2
(4300 2475);
FORCEPROP 2 LAST $XR0 143 
J 0
(4489 2475);
DISPLAY 0.638298 (4489 2475);
PAINT MONO (4489 2475);
FORCEPROP 2 LAST CDS_LIB standard
J 0
(4300 2475);
PAINT MONO (4300 2475);
DISPLAY INVISIBLE (4300 2475);
FORCEPROP 1 LAST OFFPAGE TRUE
J 0
(4625 2350);
DISPLAY 0.872340 (4625 2350);
PAINT GREEN (4625 2350);
DISPLAY INVISIBLE (4625 2350);
FORCEPROP 1 LAST COMMENT_BODY TRUE
J 0
(4255 2380);
DISPLAY 0.872340 (4255 2380);
PAINT GREEN (4255 2380);
DISPLAY INVISIBLE (4255 2380);
FORCEPROP 2 LAST PATH I75
J 0
(4500 2525);
DISPLAY 1.021277 (4500 2525);
DISPLAY INVISIBLE (4500 2525);
FORCEADD OFFPAGE..2
(2800 2325);
FORCEPROP 2 LAST $XR1 150 
J 0
(2989 2289);
DISPLAY 0.638298 (2989 2289);
PAINT MONO (2989 2289);
FORCEPROP 2 LAST $XR0 132 
J 0
(2989 2325);
DISPLAY 0.638298 (2989 2325);
PAINT MONO (2989 2325);
FORCEPROP 2 LAST CDS_LIB standard
J 0
(2800 2325);
PAINT MONO (2800 2325);
DISPLAY INVISIBLE (2800 2325);
FORCEPROP 1 LAST OFFPAGE TRUE
J 0
(3125 2200);
DISPLAY 0.872340 (3125 2200);
PAINT GREEN (3125 2200);
DISPLAY INVISIBLE (3125 2200);
FORCEPROP 1 LAST COMMENT_BODY TRUE
J 0
(2755 2230);
DISPLAY 0.872340 (2755 2230);
PAINT GREEN (2755 2230);
DISPLAY INVISIBLE (2755 2230);
FORCEPROP 2 LAST PATH I76
J 0
(3125 2375);
DISPLAY 1.021277 (3125 2375);
DISPLAY INVISIBLE (3125 2375);
FORCEADD Q_CAP..1
R 2
(-525 1375);
FORCEPROP 1 LAST LOCATION C1827
J 2
(-575 1475);
DISPLAY 0.978723 (-575 1475);
FORCEPROP 2 LAST $SEC 1
J 0
(-575 1575);
DISPLAY 0.680851 (-575 1575);
PAINT MONO (-575 1575);
DISPLAY INVISIBLE (-575 1575);
FORCEPROP 2 LAST CDS_SEC 1
J 0
(-575 1575);
DISPLAY 1.021277 (-575 1575);
DISPLAY INVISIBLE (-575 1575);
FORCEPROP 1 LASTPIN (-525 1475) $PN 1
J 2
(-535 1455);
DISPLAY 0.787234 (-535 1455);
FORCEPROP 1 LASTPIN (-525 1275) $PN 2
J 2
(-535 1255);
DISPLAY 0.787234 (-535 1255);
FORCEPROP 1 LAST TOLERANCE 10%
J 2
(-575 1325);
DISPLAY 0.510638 (-575 1325);
FORCEPROP 1 LAST VOLTAGE 25V
J 2
(-575 1375);
DISPLAY 0.510638 (-575 1375);
FORCEPROP 1 LAST VALUE 0.1UF
J 2
(-575 1425);
DISPLAY 0.510638 (-575 1425);
FORCEPROP 1 LAST MATERIAL X7R
J 2
(-575 1275);
DISPLAY 0.510638 (-575 1275);
FORCEPROP 1 LAST PACK_TYPE 0402
J 2
(-575 1175);
DISPLAY 0.510638 (-575 1175);
FORCEPROP 2 LAST CDS_LIB pure_quanta
J 0
(-525 1375);
PAINT MONO (-525 1375);
DISPLAY INVISIBLE (-525 1375);
FORCEPROP 1 LAST PATH I77
J 2
(-575 1525);
DISPLAY 0.978723 (-575 1525);
PAINT WHITE (-575 1525);
DISPLAY INVISIBLE (-575 1525);
FORCEPROP 1 LAST PART_NUMBER CH4104K1B00
J 2
(-575 1225);
DISPLAY 0.510638 (-575 1225);
DISPLAY INVISIBLE (-575 1225);
FORCEADD 74CBTLV3126PW..1
R 2
(225 850);
FORCEPROP 1 LAST LOCATION U223
J 2
(473 1308);
DISPLAY 0.723404 (473 1308);
PAINT GREEN (473 1308);
FORCEPROP 2 LAST $SEC 1
J 0
(450 1450);
DISPLAY 0.680851 (450 1450);
PAINT MONO (450 1450);
DISPLAY INVISIBLE (450 1450);
FORCEPROP 2 LAST CDS_SEC 1
J 0
(450 1450);
DISPLAY 1.021277 (450 1450);
DISPLAY INVISIBLE (450 1450);
FORCEPROP 2 LASTPIN (625 600) $PN 2
J 0
(635 610);
DISPLAY 0.808511 (635 610);
FORCEPROP 2 LASTPIN (-175 600) $PN 3
J 2
(-185 610);
DISPLAY 0.808511 (-185 610);
FORCEPROP 2 LASTPIN (625 550) $PN 1
J 0
(635 560);
DISPLAY 0.808511 (635 560);
FORCEPROP 2 LASTPIN (625 750) $PN 5
J 0
(635 760);
DISPLAY 0.808511 (635 760);
FORCEPROP 2 LASTPIN (-175 750) $PN 6
J 2
(-185 760);
DISPLAY 0.808511 (-185 760);
FORCEPROP 2 LASTPIN (625 700) $PN 4
J 0
(635 710);
DISPLAY 0.808511 (635 710);
FORCEPROP 2 LASTPIN (625 900) $PN 9
J 0
(635 910);
DISPLAY 0.808511 (635 910);
FORCEPROP 2 LASTPIN (-175 900) $PN 8
J 2
(-185 910);
DISPLAY 0.808511 (-185 910);
FORCEPROP 2 LASTPIN (625 850) $PN 10
J 0
(635 860);
DISPLAY 0.808511 (635 860);
FORCEPROP 2 LASTPIN (625 1050) $PN 12
J 0
(635 1060);
DISPLAY 0.808511 (635 1060);
FORCEPROP 2 LASTPIN (-175 1050) $PN 11
J 2
(-185 1060);
DISPLAY 0.808511 (-185 1060);
FORCEPROP 2 LASTPIN (625 1000) $PN 13
J 0
(635 1010);
DISPLAY 0.808511 (635 1010);
FORCEPROP 2 LASTPIN (-175 550) $PN 7
J 2
(-185 560);
DISPLAY 0.808511 (-185 560);
FORCEPROP 2 LASTPIN (-175 1100) $PN 14
J 2
(-185 1110);
DISPLAY 0.808511 (-185 1110);
FORCEPROP 2 LAST PART_TYPE SMLF
J 2
(450 1400);
DISPLAY 1.021277 (450 1400);
FORCEPROP 1 LAST MATERIAL IC
J 2
(473 1203);
DISPLAY 0.723404 (473 1203);
PAINT GREEN (473 1203);
FORCEPROP 2 LAST VALUE 74CBTLV3126PW
J 2
(450 1350);
DISPLAY 1.021277 (450 1350);
FORCEPROP 2 LAST CDS_LIB pure_quanta
J 2
(225 850);
PAINT MONO (225 850);
DISPLAY INVISIBLE (225 850);
FORCEPROP 1 LAST NEEDS_NO_SIZE TRUE
J 2
(-25 540);
DISPLAY 0.723404 (-25 540);
PAINT GREEN (-25 540);
DISPLAY INVISIBLE (-25 540);
FORCEPROP 1 LAST CDS_LMAN_SYM_OUTLINE -250,350,250,-350
J 2
(225 850);
DISPLAY 0.468085 (225 850);
PAINT GREEN (225 850);
DISPLAY INVISIBLE (225 850);
FORCEPROP 1 LAST PATH I78
J 2
(-25 500);
DISPLAY 0.723404 (-25 500);
PAINT GREEN (-25 500);
DISPLAY INVISIBLE (-25 500);
FORCEPROP 1 LAST PART_NUMBER AL003126K08
J 2
(473 1258);
DISPLAY 0.723404 (473 1258);
PAINT GREEN (473 1258);
DISPLAY INVISIBLE (473 1258);
FORCEADD Q_RES..1
R 1
(3275 2275);
FORCEPROP 1 LAST LOCATION R3244
J 0
(3325 2225);
DISPLAY 0.978723 (3325 2225);
FORCEPROP 0 LAST $SEC 1
R 1
J 0
(3375 2325);
DISPLAY 0.680851 (3375 2325);
PAINT MONO (3375 2325);
DISPLAY INVISIBLE (3375 2325);
FORCEPROP 0 LAST CDS_SEC 1
R 1
J 0
(3375 2325);
DISPLAY 1.021277 (3375 2325);
DISPLAY INVISIBLE (3375 2325);
FORCEPROP 1 LASTPIN (3275 2175) $PN 1
R 1
J 0
(3263 2187);
DISPLAY 0.787234 (3263 2187);
PAINT MONO (3263 2187);
FORCEPROP 1 LASTPIN (3275 2375) $PN 2
R 1
J 0
(3263 2337);
DISPLAY 0.787234 (3263 2337);
PAINT MONO (3263 2337);
FORCEPROP 1 LAST MATERIAL CHIP
J 0
(3325 2200);
DISPLAY 0.638298 (3325 2200);
FORCEPROP 1 LAST VALUE 0
J 2
(3375 2275);
DISPLAY 0.638298 (3375 2275);
FORCEPROP 2 LAST CDS_LIB pure_quanta
R 1
J 0
(3275 2275);
DISPLAY INVISIBLE (3275 2275);
FORCEPROP 1 LAST WATTAGE 1/16W
R 1
J 2
(3425 2250);
DISPLAY 0.510638 (3425 2250);
PAINT SKYBLUE (3425 2250);
DISPLAY INVISIBLE (3425 2250);
FORCEPROP 1 LAST PACK_TYPE 0402LF
R 1
J 0
(3425 2525);
DISPLAY 0.510638 (3425 2525);
PAINT SKYBLUE (3425 2525);
DISPLAY INVISIBLE (3425 2525);
FORCEPROP 1 LAST TOLERANCE 5%
R 1
J 0
(3375 2275);
DISPLAY 0.510638 (3375 2275);
PAINT SKYBLUE (3375 2275);
DISPLAY INVISIBLE (3375 2275);
FORCEPROP 1 LAST PATH I79
R 1
J 0
(3125 2225);
DISPLAY 0.978723 (3125 2225);
PAINT WHITE (3125 2225);
DISPLAY INVISIBLE (3125 2225);
FORCEPROP 1 LAST PART_NUMBER CS00002JB13
J 0
(3325 2150);
DISPLAY 0.510638 (3325 2150);
DISPLAY INVISIBLE (3325 2150);
FORCEADD 74LVC1G126SE7..1
(-1300 -425);
FORCEPROP 1 LAST LOCATION U286
J 0
(-1194 -594);
DISPLAY 0.723404 (-1194 -594);
PAINT GREEN (-1194 -594);
FORCEPROP 0 LAST $SEC 1
J 0
(-1175 -200);
DISPLAY 0.680851 (-1175 -200);
PAINT MONO (-1175 -200);
DISPLAY INVISIBLE (-1175 -200);
FORCEPROP 0 LAST CDS_SEC 1
J 0
(-1175 -200);
DISPLAY 1.021277 (-1175 -200);
DISPLAY INVISIBLE (-1175 -200);
FORCEPROP 0 LASTPIN (-1550 -375) $PN 2
J 2
(-1560 -365);
DISPLAY 0.680851 (-1560 -365);
PAINT MONO (-1560 -365);
FORCEPROP 0 LASTPIN (-1300 -675) $PN 3
R 1
J 2
(-1310 -685);
DISPLAY 0.680851 (-1310 -685);
PAINT MONO (-1310 -685);
FORCEPROP 0 LASTPIN (-1550 -475) $PN 1
J 2
(-1560 -465);
DISPLAY 0.680851 (-1560 -465);
PAINT MONO (-1560 -465);
FORCEPROP 0 LASTPIN (-1300 -175) $PN 5
R 1
J 0
(-1310 -165);
DISPLAY 0.680851 (-1310 -165);
PAINT MONO (-1310 -165);
FORCEPROP 0 LASTPIN (-1050 -425) $PN 4
J 0
(-1040 -415);
DISPLAY 0.680851 (-1040 -415);
PAINT MONO (-1040 -415);
FORCEPROP 1 LAST MATERIAL IC
J 0
(-1194 -868);
DISPLAY 0.723404 (-1194 -868);
PAINT GREEN (-1194 -868);
FORCEPROP 2 LAST VALUE 74LVC1G126SE-7
J 0
(-1175 -300);
DISPLAY 0.638298 (-1175 -300);
FORCEPROP 2 LAST PART_TYPE SMLF
J 0
(-1175 -250);
DISPLAY 0.638298 (-1175 -250);
FORCEPROP 1 LAST NEEDS_NO_SIZE TRUE
J 0
(-1300 -425);
DISPLAY 0.723404 (-1300 -425);
PAINT GREEN (-1300 -425);
DISPLAY INVISIBLE (-1300 -425);
FORCEPROP 1 LAST CDS_LMAN_SYM_OUTLINE -100,100,100,-100
J 0
(-1300 -425);
DISPLAY 0.468085 (-1300 -425);
PAINT GREEN (-1300 -425);
DISPLAY INVISIBLE (-1300 -425);
FORCEPROP 2 LAST CDS_LIB pure_quanta
J 0
(-1300 -425);
DISPLAY INVISIBLE (-1300 -425);
FORCEPROP 1 LAST PATH I80
J 0
(-1300 -425);
DISPLAY 0.723404 (-1300 -425);
PAINT GREEN (-1300 -425);
DISPLAY INVISIBLE (-1300 -425);
FORCEPROP 1 LAST PART_NUMBER AL1G0126009
J 0
(-1194 -741);
DISPLAY 0.723404 (-1194 -741);
PAINT GREEN (-1194 -741);
DISPLAY INVISIBLE (-1194 -741);
FORCEADD Q_RES..1
(-2875 -475);
FORCEPROP 1 LAST LOCATION R3203
J 0
(-3125 -475);
DISPLAY 0.638298 (-3125 -475);
FORCEPROP 2 LAST $SEC 1
J 0
(-2925 -275);
DISPLAY 0.680851 (-2925 -275);
PAINT MONO (-2925 -275);
DISPLAY INVISIBLE (-2925 -275);
FORCEPROP 2 LAST CDS_SEC 1
J 0
(-2925 -275);
DISPLAY 1.021277 (-2925 -275);
DISPLAY INVISIBLE (-2925 -275);
FORCEPROP 1 LASTPIN (-2975 -475) $PN 1
J 0
(-2963 -463);
DISPLAY 0.787234 (-2963 -463);
FORCEPROP 1 LASTPIN (-2775 -475) $PN 2
J 0
(-2813 -463);
DISPLAY 0.787234 (-2813 -463);
FORCEPROP 1 LAST WATTAGE 1/16W
J 2
(-2700 -625);
DISPLAY 0.510638 (-2700 -625);
FORCEPROP 1 LAST PACK_TYPE 0402LF
J 0
(-2975 -550);
DISPLAY 0.510638 (-2975 -550);
FORCEPROP 1 LAST MATERIAL CHIP
J 0
(-2975 -600);
DISPLAY 0.510638 (-2975 -600);
FORCEPROP 1 LAST TOLERANCE 1%
J 0
(-2650 -475);
DISPLAY 0.510638 (-2650 -475);
FORCEPROP 1 LAST VALUE 33.2
J 2
(-2675 -475);
DISPLAY 0.510638 (-2675 -475);
FORCEPROP 2 LAST CDS_LIB pure_quanta
J 0
(-2875 -475);
PAINT MONO (-2875 -475);
DISPLAY INVISIBLE (-2875 -475);
FORCEPROP 1 LAST PATH I81
J 0
(-2925 -325);
DISPLAY 0.978723 (-2925 -325);
PAINT WHITE (-2925 -325);
DISPLAY INVISIBLE (-2925 -325);
FORCEPROP 1 LAST PART_NUMBER CS03322FB03
J 0
(-2975 -650);
DISPLAY 0.510638 (-2975 -650);
DISPLAY INVISIBLE (-2975 -650);
FORCEADD OFFPAGE..1
(-3900 -475);
FORCEPROP 2 LAST $XR2 139 
J 0
(-4392 -475);
DISPLAY 0.638298 (-4392 -475);
PAINT MONO (-4392 -475);
FORCEPROP 2 LAST $XR1 142 
J 0
(-4272 -475);
DISPLAY 0.638298 (-4272 -475);
PAINT MONO (-4272 -475);
FORCEPROP 2 LAST $XR0 137 
J 0
(-4152 -475);
DISPLAY 0.638298 (-4152 -475);
PAINT MONO (-4152 -475);
FORCEPROP 2 LAST CDS_LIB standard
J 0
(-3900 -475);
PAINT MONO (-3900 -475);
DISPLAY INVISIBLE (-3900 -475);
FORCEPROP 1 LAST OFFPAGE TRUE
J 0
(-3575 -600);
DISPLAY 0.872340 (-3575 -600);
PAINT GREEN (-3575 -600);
DISPLAY INVISIBLE (-3575 -600);
FORCEPROP 1 LAST COMMENT_BODY TRUE
J 0
(-3775 -575);
DISPLAY 0.872340 (-3775 -575);
PAINT GREEN (-3775 -575);
DISPLAY INVISIBLE (-3775 -575);
FORCEPROP 2 LAST PATH I82
J 0
(-4175 -425);
DISPLAY 1.021277 (-4175 -425);
DISPLAY INVISIBLE (-4175 -425);
FORCEADD UNIVERSAL_GND..1
(-1300 -800);
FORCEPROP 3 LASTPIN (-1300 -750) SIG_NAME GND\g
J 0
(-1290 -740);
DISPLAY 0.659574 (-1290 -740);
PAINT MONO (-1290 -740);
DISPLAY INVISIBLE (-1290 -740);
FORCEPROP 2 LAST CDS_LIB pure_quanta_power
J 0
(-1300 -800);
PAINT MONO (-1300 -800);
DISPLAY INVISIBLE (-1300 -800);
FORCEPROP 1 LAST HDL_POWER GND
J 1
(-1275 -875);
DISPLAY 0.872340 (-1275 -875);
PAINT GREEN (-1275 -875);
DISPLAY INVISIBLE (-1275 -875);
FORCEPROP 1 LAST PATH I83
J 0
(-1225 -800);
DISPLAY 0.872340 (-1225 -800);
PAINT AQUA (-1225 -800);
DISPLAY INVISIBLE (-1225 -800);
FORCEADD OFFPAGE..5
R 2
(1075 -425);
FORCEPROP 2 LAST $XR0 139 
J 0
(1264 -425);
DISPLAY 0.638298 (1264 -425);
PAINT MONO (1264 -425);
FORCEPROP 2 LAST CDS_LIB standard
J 2
(1075 -425);
DISPLAY INVISIBLE (1075 -425);
FORCEPROP 1 LAST OFFPAGE TRUE
J 2
(750 -550);
DISPLAY 0.872340 (750 -550);
PAINT GREEN (750 -550);
DISPLAY INVISIBLE (750 -550);
FORCEPROP 1 LAST COMMENT_BODY TRUE
J 2
(975 -500);
DISPLAY 0.872340 (975 -500);
PAINT GREEN (975 -500);
DISPLAY INVISIBLE (975 -500);
FORCEPROP 2 LAST PATH I84
J 2
(1025 -350);
DISPLAY 1.021277 (1025 -350);
DISPLAY INVISIBLE (1025 -350);
FORCEADD Q_RES..1
(-75 -950);
FORCEPROP 1 LAST LOCATION R3206
J 0
(-300 -950);
DISPLAY 0.787234 (-300 -950);
FORCEPROP 0 LAST $SEC 1
J 0
(175 -825);
DISPLAY 0.680851 (175 -825);
PAINT MONO (175 -825);
DISPLAY INVISIBLE (175 -825);
FORCEPROP 0 LAST CDS_SEC 1
J 0
(175 -825);
DISPLAY 0.680851 (175 -825);
DISPLAY INVISIBLE (175 -825);
FORCEPROP 1 LASTPIN (-175 -950) $PN 1
J 0
(-163 -938);
DISPLAY 0.787234 (-163 -938);
PAINT MONO (-163 -938);
FORCEPROP 1 LASTPIN (25 -950) $PN 2
J 0
(-13 -938);
DISPLAY 0.787234 (-13 -938);
PAINT MONO (-13 -938);
FORCEPROP 1 LAST TOLERANCE 5%
J 0
(75 -950);
DISPLAY 0.510638 (75 -950);
FORCEPROP 1 LAST VALUE 0
J 2
(50 -950);
DISPLAY 0.510638 (50 -950);
FORCEPROP 1 LAST PACK_TYPE 0402LF
J 0
(-175 -850);
DISPLAY 0.510638 (-175 -850);
FORCEPROP 1 LAST WATTAGE 1/16W
J 2
(175 -850);
DISPLAY 0.510638 (175 -850);
FORCEPROP 1 LAST MATERIAL EMPTY
J 0
(150 -950);
DISPLAY 0.510638 (150 -950);
PAINT RED (150 -950);
FORCEPROP 2 LAST CDS_LIB pure_quanta
J 0
(-75 -950);
DISPLAY INVISIBLE (-75 -950);
FORCEPROP 1 LAST PATH I85
J 0
(-125 -800);
DISPLAY 0.978723 (-125 -800);
PAINT WHITE (-125 -800);
DISPLAY INVISIBLE (-125 -800);
FORCEPROP 1 LAST PART_NUMBER CS00002JB13
J 0
(-175 -900);
DISPLAY 0.510638 (-175 -900);
DISPLAY INVISIBLE (-175 -900);
FORCEADD Q_RES..1
(-75 -425);
FORCEPROP 1 LAST LOCATION R3205
J 0
(-300 -425);
DISPLAY 0.787234 (-300 -425);
FORCEPROP 0 LAST $SEC 1
J 0
(175 -300);
DISPLAY 0.680851 (175 -300);
PAINT MONO (175 -300);
DISPLAY INVISIBLE (175 -300);
FORCEPROP 0 LAST CDS_SEC 1
J 0
(175 -300);
DISPLAY 0.680851 (175 -300);
DISPLAY INVISIBLE (175 -300);
FORCEPROP 1 LASTPIN (-175 -425) $PN 1
J 0
(-163 -413);
DISPLAY 0.787234 (-163 -413);
PAINT MONO (-163 -413);
FORCEPROP 1 LASTPIN (25 -425) $PN 2
J 0
(-13 -413);
DISPLAY 0.787234 (-13 -413);
PAINT MONO (-13 -413);
FORCEPROP 1 LAST VALUE 0
J 2
(50 -425);
DISPLAY 0.510638 (50 -425);
FORCEPROP 1 LAST PACK_TYPE 0402LF
J 0
(-175 -325);
DISPLAY 0.510638 (-175 -325);
FORCEPROP 1 LAST MATERIAL CHIP
J 0
(150 -425);
DISPLAY 0.510638 (150 -425);
FORCEPROP 1 LAST TOLERANCE 5%
J 0
(75 -425);
DISPLAY 0.510638 (75 -425);
FORCEPROP 1 LAST WATTAGE 1/16W
J 2
(175 -325);
DISPLAY 0.510638 (175 -325);
FORCEPROP 2 LAST CDS_LIB pure_quanta
J 0
(-75 -425);
DISPLAY INVISIBLE (-75 -425);
FORCEPROP 1 LAST PATH I86
J 0
(-125 -275);
DISPLAY 0.978723 (-125 -275);
PAINT WHITE (-125 -275);
DISPLAY INVISIBLE (-125 -275);
FORCEPROP 1 LAST PART_NUMBER CS00002JB13
J 0
(-175 -375);
DISPLAY 0.510638 (-175 -375);
DISPLAY INVISIBLE (-175 -375);
FORCEADD OFFPAGE..1
(-1350 -950);
FORCEPROP 2 LAST $XR0 81 
J 0
(-1571 -950);
DISPLAY 0.638298 (-1571 -950);
PAINT MONO (-1571 -950);
FORCEPROP 2 LAST CDS_LIB standard
J 0
(-1350 -950);
DISPLAY INVISIBLE (-1350 -950);
FORCEPROP 1 LAST OFFPAGE TRUE
J 0
(-1025 -1075);
DISPLAY 0.872340 (-1025 -1075);
PAINT GREEN (-1025 -1075);
DISPLAY INVISIBLE (-1025 -1075);
FORCEPROP 1 LAST COMMENT_BODY TRUE
J 0
(-1225 -1050);
DISPLAY 0.872340 (-1225 -1050);
PAINT GREEN (-1225 -1050);
DISPLAY INVISIBLE (-1225 -1050);
FORCEPROP 2 LAST PATH I9
J 0
(-1600 -900);
DISPLAY 1.021277 (-1600 -900);
DISPLAY INVISIBLE (-1600 -900);
FORCEADD DNS..2
(3475 2475);
PAINT RED (3475 2475);
FORCEPROP 2 LAST CDS_LIB mstr_misc
J 0
(3475 2475);
DISPLAY INVISIBLE (3475 2475);
FORCEPROP 1 LAST COMMENT_BODY TRUE
R 1
J 0
(3550 2250);
DISPLAY 0.872340 (3550 2250);
PAINT GREEN (3550 2250);
DISPLAY INVISIBLE (3550 2250);
FORCEADD DNS..2
(1925 2325);
PAINT RED (1925 2325);
FORCEPROP 2 LAST CDS_LIB mstr_misc
J 0
(1925 2325);
DISPLAY INVISIBLE (1925 2325);
FORCEPROP 1 LAST COMMENT_BODY TRUE
R 1
J 0
(2000 2100);
DISPLAY 0.872340 (2000 2100);
PAINT GREEN (2000 2100);
DISPLAY INVISIBLE (2000 2100);
FORCEADD DNS..2
(1925 2175);
PAINT RED (1925 2175);
FORCEPROP 2 LAST CDS_LIB mstr_misc
J 0
(1925 2175);
DISPLAY INVISIBLE (1925 2175);
FORCEPROP 1 LAST COMMENT_BODY TRUE
R 1
J 0
(2000 1950);
DISPLAY 0.872340 (2000 1950);
PAINT GREEN (2000 1950);
DISPLAY INVISIBLE (2000 1950);
FORCEADD DNS..2
(1925 2025);
PAINT RED (1925 2025);
FORCEPROP 2 LAST CDS_LIB mstr_misc
J 0
(1925 2025);
DISPLAY INVISIBLE (1925 2025);
FORCEPROP 1 LAST COMMENT_BODY TRUE
R 1
J 0
(2000 1800);
DISPLAY 0.872340 (2000 1800);
PAINT GREEN (2000 1800);
DISPLAY INVISIBLE (2000 1800);
FORCEADD DNS..2
(1925 900);
PAINT RED (1925 900);
FORCEPROP 2 LAST CDS_LIB mstr_misc
J 0
(1925 900);
DISPLAY INVISIBLE (1925 900);
FORCEPROP 1 LAST COMMENT_BODY TRUE
R 1
J 0
(2000 675);
DISPLAY 0.872340 (2000 675);
PAINT GREEN (2000 675);
DISPLAY INVISIBLE (2000 675);
FORCEADD DNS..2
(1925 775);
PAINT RED (1925 775);
FORCEPROP 2 LAST CDS_LIB mstr_misc
J 0
(1925 775);
DISPLAY INVISIBLE (1925 775);
FORCEPROP 1 LAST COMMENT_BODY TRUE
R 1
J 0
(2000 550);
DISPLAY 0.872340 (2000 550);
PAINT GREEN (2000 550);
DISPLAY INVISIBLE (2000 550);
FORCEADD DNS..2
(1925 600);
PAINT RED (1925 600);
FORCEPROP 2 LAST CDS_LIB mstr_misc
J 0
(1925 600);
DISPLAY INVISIBLE (1925 600);
FORCEPROP 1 LAST COMMENT_BODY TRUE
R 1
J 0
(2000 375);
DISPLAY 0.872340 (2000 375);
PAINT GREEN (2000 375);
DISPLAY INVISIBLE (2000 375);
FORCEADD DNS..2
(-50 -975);
PAINT RED (-50 -975);
FORCEPROP 2 LAST CDS_LIB mstr_misc
J 0
(-50 -975);
DISPLAY INVISIBLE (-50 -975);
FORCEPROP 1 LAST COMMENT_BODY TRUE
R 1
J 0
(25 -1200);
DISPLAY 0.872340 (25 -1200);
PAINT GREEN (25 -1200);
DISPLAY INVISIBLE (25 -1200);
FORCEADD QUANTA_TITLE_BLOCK_C..1
(4625 -3250);
FORCEPROP 0 LAST CDS_CON_LAST_MODIFIED Thu Sep 14 16:12:24 2023
J 0
(2740 -3235);
PAINT MONO (2740 -3235);
DISPLAY INVISIBLE (2740 -3235);
FORCEPROP 2 LAST CUSTOM_TXT_CDS <XR_PAGE_TITLE>
J 0
(-3265 2000);
DISPLAY 0.638298 (-3265 2000);
PAINT PINK (-3265 2000);
DISPLAY INVISIBLE (-3265 2000);
FORCEPROP 2 LAST CUSTOM_TXT_CDS <CON_LAST_MODIFIED>
J 0
(2740 -3235);
DISPLAY 0.978723 (2740 -3235);
FORCEPROP 2 LAST CUSTOM_TXT_CDS <NAME_1>
J 0
(1450 -3075);
FORCEPROP 2 LAST CUSTOM_TXT_CDS <Q_NUMBER>
J 0
(3222 -3147);
DISPLAY 1.212766 (3222 -3147);
FORCEPROP 2 LAST CUSTOM_TXT_CDS <NAME_2>
J 0
(1450 -3200);
FORCEPROP 2 LAST CUSTOM_TXT_CDS <Q_REV>
J 0
(4441 -3147);
DISPLAY 1.212766 (4441 -3147);
FORCEPROP 2 LAST CUSTOM_TXT_CDS <Q_PROJ>
J 0
(2243 -3148);
DISPLAY 1.212766 (2243 -3148);
FORCEPROP 1 LAST CUSTOM_TXT_CDS <CON_PAGE_NUM> OF <CON_TOTAL_PAGES>
J 0
(4179 -3232);
DISPLAY 0.978723 (4179 -3232);
FORCEPROP 1 LAST Q_TITLE PCIE - V3_2 OCP3.0 (2/3)
J 0
(-4741 -3224);
DISPLAY 1.957447 (-4741 -3224);
PAINT GREEN (-4741 -3224);
FORCEPROP 2 LAST CDS_LIB pure_quanta
J 0
(4625 -3250);
PAINT MONO (4625 -3250);
DISPLAY INVISIBLE (4625 -3250);
FORCEPROP 1 LAST CDS_LMAN_SYM_OUTLINE -9475,6775,100,-125
J 0
(4625 -3250);
DISPLAY 0.468085 (4625 -3250);
PAINT GREEN (4625 -3250);
DISPLAY INVISIBLE (4625 -3250);
FORCEPROP 2 LAST PAGE_BORDER TRUE
J 0
(-3265 2000);
DISPLAY 0.638298 (-3265 2000);
PAINT PINK (-3265 2000);
DISPLAY INVISIBLE (-3265 2000);
FORCEPROP 2 LAST CDS_XR_PAGE_TITLE CR-138 : @T6G_MB_LIB.T6G(SCH_1):PAGE138
J 0
(-3265 2000);
DISPLAY 0.638298 (-3265 2000);
PAINT PINK (-3265 2000);
DISPLAY INVISIBLE (-3265 2000);
FORCEPROP 1 LAST Q_DEPT BU9
J 1
(862 -3201);
DISPLAY 1.957447 (862 -3201);
PAINT GREEN (862 -3201);
DISPLAY INVISIBLE (862 -3201);
FORCEPROP 1 LAST COMMENT_BODY TRUE
J 0
(4637 -3263);
DISPLAY 0.978723 (4637 -3263);
PAINT GREEN (4637 -3263);
DISPLAY INVISIBLE (4637 -3263);
WIRE 16 -1 (275 -725)(275 -800);
WIRE 16 -1 (-1600 -125)(-1600 -200);
WIRE 16 -1 (-325 550)(-175 550);
FORCEPROP 0 LAST VOLTAGE 0
J 0
(-250 550);
PAINT MONO (-250 550);
DISPLAY INVISIBLE (-250 550);
FORCEPROP 0 LAST CDS_PHYS_NET_NAME GND
J 0
(-250 597);
PAINT MONO (-250 597);
DISPLAY INVISIBLE (-250 597);
WIRE 16 -1 (-325 550)(-325 475);
WIRE 16 -1 (-525 1275)(-525 1200);
WIRE 16 -1 (-325 1975)(-175 1975);
FORCEPROP 0 LAST VOLTAGE 0
J 0
(-250 1975);
PAINT MONO (-250 1975);
DISPLAY INVISIBLE (-250 1975);
FORCEPROP 0 LAST CDS_PHYS_NET_NAME GND
J 0
(-250 2022);
PAINT MONO (-250 2022);
DISPLAY INVISIBLE (-250 2022);
WIRE 16 -1 (-325 1975)(-325 1900);
WIRE 16 -1 (-525 2700)(-525 2625);
WIRE 16 -1 (-1300 -675)(-1300 -750);
WIRE 16 -1 (-1300 -950)(-175 -950);
FORCEPROP 2 LAST SIG_NAME FM_NCSI_OCP_V3_2_R_OE
J 0
(-1135 -940);
DISPLAY 0.553191 (-1135 -940);
PAINT WHITE (-1135 -940);
WIRE 16 -1 (850 550)(850 -425);
WIRE 16 -1 (850 700)(850 550);
WIRE 16 -1 (625 550)(850 550);
WIRE 16 -1 (850 -425)(1025 -425);
WIRE 16 -1 (850 -425)(850 -950);
WIRE 16 -1 (275 -425)(850 -425);
FORCEPROP 2 LAST SIG_NAME FB_BMC_ISOLATE1
J 0
(340 -415);
DISPLAY 0.553191 (340 -415);
PAINT WHITE (340 -415);
WIRE 16 -1 (25 -425)(275 -425);
WIRE 16 -1 (275 -525)(275 -425);
WIRE 16 -1 (850 -950)(25 -950);
WIRE 16 -1 (850 850)(850 700);
WIRE 16 -1 (625 700)(850 700);
WIRE 16 -1 (850 1000)(850 850);
WIRE 16 -1 (625 850)(850 850);
WIRE 16 -1 (850 1975)(850 1000);
WIRE 16 -1 (625 1000)(850 1000);
WIRE 16 -1 (850 2125)(850 1975);
WIRE 16 -1 (625 1975)(850 1975);
WIRE 16 -1 (850 2275)(850 2125);
WIRE 16 -1 (625 2125)(850 2125);
WIRE 16 -1 (850 2425)(850 2275);
WIRE 16 -1 (625 2275)(850 2275);
WIRE 16 -1 (625 2425)(850 2425);
WIRE 16 -1 (-1050 -425)(-175 -425);
FORCEPROP 2 LAST SIG_NAME FB_BMC_ISOLATE_R2
J 0
(-885 -415);
DISPLAY 0.553191 (-885 -415);
PAINT WHITE (-885 -415);
FORCEPROP 2 LASTPROP $XRERR UNIQUE?
J 0
(-1125 -415);
DISPLAY 0.638298 (-1125 -415);
PAINT MONO (-1125 -415);
DISPLAY INVISIBLE (-1125 -415);
WIRE 16 -1 (-1300 -175)(-1300 150);
WIRE 16 -1 (-1300 150)(-1600 150);
WIRE 16 -1 (-1600 150)(-1600 200);
WIRE 16 -1 (-1600 150)(-1600 75);
WIRE 16 -1 (-1550 -475)(-2775 -475);
FORCEPROP 0 LAST CDS_PHYS_NET_NAME OCP_V3_2_AUX_PWR_EN_R1
J 0
(-2410 -433);
PAINT MONO (-2410 -433);
DISPLAY INVISIBLE (-2410 -433);
FORCEPROP 2 LAST SIG_NAME OCP_V3_2_AUX_PWR_EN_R1
J 0
(-2485 -465);
DISPLAY 0.680851 (-2485 -465);
PAINT WHITE (-2485 -465);
FORCEPROP 2 LASTPROP $XRERR UNIQUE?
J 0
(-2725 -465);
DISPLAY 0.638298 (-2725 -465);
PAINT MONO (-2725 -465);
DISPLAY INVISIBLE (-2725 -465);
WIRE 16 -1 (-2500 -375)(-1550 -375);
FORCEPROP 0 LAST CDS_PHYS_NET_NAME FM_OCP_SFF_PWR_GOOD
J 0
(-2135 -333);
PAINT MONO (-2135 -333);
DISPLAY INVISIBLE (-2135 -333);
FORCEPROP 2 LAST SIG_NAME FM_OCP_V3_2_PWR_GOOD
J 0
(-2360 -365);
DISPLAY 0.680851 (-2360 -365);
PAINT WHITE (-2360 -365);
WIRE 16 -1 (2300 -2425)(2300 -2275);
WIRE 16 -1 (3275 -2275)(2300 -2275);
FORCEPROP 0 LAST CDS_PHYS_NET_NAME OCP_SFF_ISO_BIF2_EN
J 0
(2365 -2233);
PAINT MONO (2365 -2233);
DISPLAY INVISIBLE (2365 -2233);
FORCEPROP 2 LAST SIG_NAME OCP_V3_2_ISO_BIF2_EN
J 0
(2565 -2265);
DISPLAY 0.680851 (2565 -2265);
PAINT WHITE (2565 -2265);
WIRE 16 -1 (-1125 900)(-175 900);
FORCEPROP 2 LAST SIG_NAME NCSI_OCP_V3_2_TX_EN
J 0
(-1060 910);
DISPLAY 0.680851 (-1060 910);
PAINT WHITE (-1060 910);
WIRE 16 -1 (625 2025)(1800 2025);
FORCEPROP 2 LAST SIG_NAME NCSI_BMC_RXD1_R1
J 0
(915 2035);
DISPLAY 0.680851 (915 2035);
PAINT WHITE (915 2035);
FORCEPROP 2 LASTPROP $XRERR UNIQUE?
J 0
(675 2035);
DISPLAY 0.638298 (675 2035);
PAINT MONO (675 2035);
DISPLAY INVISIBLE (675 2035);
WIRE 16 -1 (2750 2025)(2000 2025);
FORCEPROP 2 LAST SIG_NAME RMII_OCP_BMC_RXD_1
J 0
(2140 2035);
DISPLAY 0.680851 (2140 2035);
PAINT WHITE (2140 2035);
WIRE 16 -1 (2875 750)(2000 750);
FORCEPROP 2 LAST SIG_NAME RMII_BMC_OCP_TXD_0
J 0
(2290 760);
DISPLAY 0.680851 (2290 760);
PAINT WHITE (2290 760);
WIRE 16 -1 (2875 600)(2000 600);
FORCEPROP 2 LAST SIG_NAME RMII_BMC_OCP_TXD_1
J 0
(2290 610);
DISPLAY 0.680851 (2290 610);
PAINT WHITE (2290 610);
WIRE 16 2175 (3200 2075)(3900 2075);
WIRE 16 2175 (3200 2675)(3200 2075);
WIRE 16 2175 (3900 2675)(3900 2075);
WIRE 16 2175 (3200 2675)(3900 2675);
FORCEPROP 0 LAST M1 CO-LAYOUT
J 0
(3300 2700);
DISPLAY 1.021277 (3300 2700);
WIRE 16 -1 (3275 2475)(3350 2475);
WIRE 16 -1 (3275 2375)(3275 2475);
WIRE 16 -1 (3275 2475)(625 2475);
FORCEPROP 0 LAST CDS_PHYS_NET_NAME OCP_SFF_RBT_ARB_IN
J 0
(990 2517);
PAINT MONO (990 2517);
DISPLAY INVISIBLE (990 2517);
FORCEPROP 2 LAST SIG_NAME OCP_V3_2_RBT_ARB_IN_R
J 0
(915 2485);
DISPLAY 0.680851 (915 2485);
PAINT WHITE (915 2485);
FORCEPROP 2 LASTPROP $XRERR UNIQUE?
J 0
(675 2485);
DISPLAY 0.638298 (675 2485);
PAINT MONO (675 2485);
DISPLAY INVISIBLE (675 2485);
WIRE 16 -1 (2750 2175)(2000 2175);
FORCEPROP 2 LAST SIG_NAME RMII_OCP_BMC_RXD_0
J 0
(2140 2185);
DISPLAY 0.680851 (2140 2185);
PAINT WHITE (2140 2185);
WIRE 16 -1 (625 2175)(1800 2175);
FORCEPROP 0 LAST CDS_PHYS_NET_NAME NCSI_BMC_RXD0_R
J 0
(690 2217);
PAINT MONO (690 2217);
DISPLAY INVISIBLE (690 2217);
FORCEPROP 2 LAST SIG_NAME NCSI_BMC_RXD0_R1
J 0
(915 2185);
DISPLAY 0.680851 (915 2185);
PAINT WHITE (915 2185);
FORCEPROP 2 LASTPROP $XRERR UNIQUE?
J 0
(675 2185);
DISPLAY 0.638298 (675 2185);
PAINT MONO (675 2185);
DISPLAY INVISIBLE (675 2185);
WIRE 16 -1 (-1125 2175)(-175 2175);
FORCEPROP 0 LAST CDS_PHYS_NET_NAME NCSI_OCP_SFF_RXD0
J 0
(-1060 2217);
PAINT MONO (-1060 2217);
DISPLAY INVISIBLE (-1060 2217);
FORCEPROP 2 LAST SIG_NAME NCSI_OCP_V3_2_RXD0
J 0
(-985 2185);
DISPLAY 0.680851 (-985 2185);
PAINT WHITE (-985 2185);
WIRE 16 -1 (2875 900)(2000 900);
FORCEPROP 2 LAST SIG_NAME RMII_BMC_OCP_TX_EN
J 0
(2290 910);
DISPLAY 0.680851 (2290 910);
PAINT WHITE (2290 910);
WIRE 16 -1 (4250 2475)(3550 2475);
FORCEPROP 2 LAST SIG_NAME OCP_V3_2_RBT_ARB_IN
J 0
(3665 2485);
DISPLAY 0.680851 (3665 2485);
PAINT WHITE (3665 2485);
WIRE 16 -1 (-175 2325)(-1125 2325);
FORCEPROP 0 LAST CDS_PHYS_NET_NAME NCSI_OCP_SFF_CRS_DV
J 0
(-1060 2367);
PAINT MONO (-1060 2367);
DISPLAY INVISIBLE (-1060 2367);
FORCEPROP 2 LAST SIG_NAME NCSI_OCP_V3_2_CRS_DV
J 0
(-985 2335);
DISPLAY 0.680851 (-985 2335);
PAINT WHITE (-985 2335);
WIRE 16 -1 (-325 2525)(-325 2975);
FORCEPROP 0 LAST CDS_PHYS_NET_NAME P3V3_AUX
J 0
(-325 2797);
PAINT MONO (-325 2797);
DISPLAY INVISIBLE (-325 2797);
FORCEPROP 0 LAST VOLTAGE 3.3
J 0
(-325 2750);
PAINT MONO (-325 2750);
DISPLAY INVISIBLE (-325 2750);
FORCEPROP 0 LAST $PHYS_NET_NAME P3V3_AUX
J 0
(-325 2844);
PAINT MONO (-325 2844);
DISPLAY INVISIBLE (-325 2844);
WIRE 16 -1 (-325 2525)(-175 2525);
FORCEPROP 0 LAST CDS_PHYS_NET_NAME P3V3_AUX
J 0
(-250 2572);
PAINT MONO (-250 2572);
DISPLAY INVISIBLE (-250 2572);
FORCEPROP 0 LAST VOLTAGE 3.3
J 0
(-250 2525);
PAINT MONO (-250 2525);
DISPLAY INVISIBLE (-250 2525);
FORCEPROP 0 LAST $PHYS_NET_NAME P3V3_AUX
J 0
(-250 2619);
PAINT MONO (-250 2619);
DISPLAY INVISIBLE (-250 2619);
WIRE 16 -1 (-525 2975)(-325 2975);
WIRE 16 -1 (-325 2975)(-325 3075);
WIRE 16 -1 (-525 2975)(-525 2900);
WIRE 16 -1 (1800 2325)(625 2325);
FORCEPROP 0 LAST CDS_PHYS_NET_NAME NCSI_BMC_CRS_DV_R
J 0
(690 2367);
PAINT MONO (690 2367);
DISPLAY INVISIBLE (690 2367);
FORCEPROP 2 LAST SIG_NAME NCSI_BMC_CRS_DV_R1
J 0
(915 2335);
DISPLAY 0.680851 (915 2335);
PAINT WHITE (915 2335);
FORCEPROP 2 LASTPROP $XRERR UNIQUE?
J 0
(675 2335);
DISPLAY 0.638298 (675 2335);
PAINT MONO (675 2335);
DISPLAY INVISIBLE (675 2335);
WIRE 16 -1 (-1125 2025)(-175 2025);
FORCEPROP 2 LAST SIG_NAME NCSI_OCP_V3_2_RXD1
J 0
(-985 2035);
DISPLAY 0.680851 (-985 2035);
PAINT WHITE (-985 2035);
WIRE 16 -1 (-1125 1050)(-175 1050);
FORCEPROP 2 LAST SIG_NAME OCP_V3_2_ISO2_RBT_ARB_OUT
J 0
(-1060 1060);
DISPLAY 0.680851 (-1060 1060);
PAINT WHITE (-1060 1060);
WIRE 16 -1 (-1125 750)(-175 750);
FORCEPROP 2 LAST SIG_NAME NCSI_OCP_V3_2_TXD0
J 0
(-1060 760);
DISPLAY 0.680851 (-1060 760);
PAINT WHITE (-1060 760);
WIRE 16 -1 (2050 -2425)(2050 -2125);
WIRE 16 -1 (3275 -2125)(2050 -2125);
FORCEPROP 0 LAST CDS_PHYS_NET_NAME OCP_SFF_ISO_BIF1_EN
J 0
(2365 -2083);
PAINT MONO (2365 -2083);
DISPLAY INVISIBLE (2365 -2083);
FORCEPROP 2 LAST SIG_NAME OCP_V3_2_ISO_BIF1_EN
J 0
(2565 -2115);
DISPLAY 0.680851 (2565 -2115);
PAINT WHITE (2565 -2115);
WIRE 16 -1 (3275 -1975)(1800 -1975);
FORCEPROP 0 LAST CDS_PHYS_NET_NAME OCP_SFF_ISO_BIF0_EN
J 0
(2365 -1933);
PAINT MONO (2365 -1933);
DISPLAY INVISIBLE (2365 -1933);
FORCEPROP 2 LAST SIG_NAME OCP_V3_2_ISO_BIF0_EN
J 0
(2565 -1965);
DISPLAY 0.680851 (2565 -1965);
PAINT WHITE (2565 -1965);
WIRE 16 -1 (1800 -2425)(1800 -1975);
WIRE 16 -1 (2050 -2700)(2300 -2700);
WIRE 16 -1 (2050 -2625)(2050 -2700);
WIRE 16 -1 (1800 -2700)(2050 -2700);
FORCEPROP 0 LAST VOLTAGE 0
J 0
(1925 -2700);
DISPLAY INVISIBLE (1925 -2700);
WIRE 16 -1 (2300 -2625)(2300 -2700);
WIRE 16 -1 (1800 -2625)(1800 -2700);
WIRE 16 -1 (1800 -2700)(1800 -2750);
WIRE 16 -1 (-325 1100)(-325 1550);
FORCEPROP 0 LAST CDS_PHYS_NET_NAME P3V3_AUX
J 0
(-325 1372);
PAINT MONO (-325 1372);
DISPLAY INVISIBLE (-325 1372);
FORCEPROP 0 LAST VOLTAGE 3.3
J 0
(-325 1325);
PAINT MONO (-325 1325);
DISPLAY INVISIBLE (-325 1325);
FORCEPROP 0 LAST $PHYS_NET_NAME P3V3_AUX
J 0
(-325 1419);
PAINT MONO (-325 1419);
DISPLAY INVISIBLE (-325 1419);
WIRE 16 -1 (-325 1100)(-175 1100);
FORCEPROP 0 LAST CDS_PHYS_NET_NAME P3V3_AUX
J 0
(-250 1147);
PAINT MONO (-250 1147);
DISPLAY INVISIBLE (-250 1147);
FORCEPROP 0 LAST VOLTAGE 3.3
J 0
(-250 1100);
PAINT MONO (-250 1100);
DISPLAY INVISIBLE (-250 1100);
FORCEPROP 0 LAST $PHYS_NET_NAME P3V3_AUX
J 0
(-250 1194);
PAINT MONO (-250 1194);
DISPLAY INVISIBLE (-250 1194);
WIRE 16 -1 (-525 1550)(-325 1550);
WIRE 16 -1 (-325 1550)(-325 1650);
WIRE 16 -1 (-525 1550)(-525 1475);
WIRE 16 -1 (2750 2325)(2000 2325);
FORCEPROP 2 LAST SIG_NAME RMII_OCP_BMC_CRSDV
J 0
(2140 2335);
DISPLAY 0.680851 (2140 2335);
PAINT WHITE (2140 2335);
WIRE 16 -1 (-2975 -475)(-3850 -475);
FORCEPROP 0 LAST CDS_PHYS_NET_NAME OCP_V3_2_AUX_PWR_EN
J 0
(-3485 -433);
PAINT MONO (-3485 -433);
DISPLAY INVISIBLE (-3485 -433);
FORCEPROP 2 LAST SIG_NAME OCP_V3_2_AUX_PWR_EN
J 0
(-3760 -465);
DISPLAY 0.680851 (-3760 -465);
PAINT WHITE (-3760 -465);
WIRE 16 -1 (-1125 600)(-175 600);
FORCEPROP 2 LAST SIG_NAME NCSI_OCP_V3_2_TXD1
J 0
(-1060 610);
DISPLAY 0.680851 (-1060 610);
PAINT WHITE (-1060 610);
WIRE 16 -1 (625 600)(1800 600);
FORCEPROP 2 LAST SIG_NAME NCSI_BMC_TXD1_R1
J 0
(915 610);
DISPLAY 0.680851 (915 610);
PAINT WHITE (915 610);
FORCEPROP 2 LASTPROP $XRERR UNIQUE?
J 0
(675 610);
DISPLAY 0.638298 (675 610);
PAINT MONO (675 610);
DISPLAY INVISIBLE (675 610);
WIRE 16 -1 (625 750)(1800 750);
FORCEPROP 2 LAST SIG_NAME NCSI_BMC_TXD0_R1
J 0
(915 760);
DISPLAY 0.680851 (915 760);
PAINT WHITE (915 760);
FORCEPROP 2 LASTPROP $XRERR UNIQUE?
J 0
(675 760);
DISPLAY 0.638298 (675 760);
PAINT MONO (675 760);
DISPLAY INVISIBLE (675 760);
WIRE 16 -1 (625 900)(1800 900);
FORCEPROP 2 LAST SIG_NAME NCSI_BMC_TX_EN_R1
J 0
(915 910);
DISPLAY 0.680851 (915 910);
PAINT WHITE (915 910);
FORCEPROP 2 LASTPROP $XRERR UNIQUE?
J 0
(675 910);
DISPLAY 0.638298 (675 910);
PAINT MONO (675 910);
DISPLAY INVISIBLE (675 910);
WIRE 16 -1 (3275 2175)(3275 1050);
WIRE 16 -1 (4275 1050)(3275 1050);
WIRE 16 -1 (625 1050)(3275 1050);
FORCEPROP 2 LAST SIG_NAME OCP_V3_2_RBT_ARB_OUT
J 0
(915 1060);
DISPLAY 0.680851 (915 1060);
PAINT WHITE (915 1060);
WIRE 16 -1 (-1125 2475)(-175 2475);
FORCEPROP 0 LAST CDS_PHYS_NET_NAME OCP_SFF_ISO_RBT_ARB_IN
J 0
(-760 2517);
PAINT MONO (-760 2517);
DISPLAY INVISIBLE (-760 2517);
FORCEPROP 2 LAST SIG_NAME OCP_V3_2_ISO1_RBT_ARB_IN
J 0
(-985 2485);
DISPLAY 0.680851 (-985 2485);
PAINT WHITE (-985 2485);
DOT 1 (3275 1050);
DOT 1 (-325 1550);
DOT 1 (275 -425);
DOT 1 (-325 2975);
DOT 1 (850 1975);
DOT 1 (850 2275);
DOT 1 (850 2125);
DOT 1 (850 1000);
DOT 1 (-1600 150);
DOT 1 (2050 -2700);
DOT 1 (1800 -2700);
DOT 1 (850 -425);
DOT 1 (3275 2475);
DOT 1 (850 850);
DOT 1 (850 700);
DOT 1 (850 550);
QUIT
